FILE_TYPE = MULTI_PHYS_TABLE;

PART 'Q_CAPP'

{========================================================================================}
:VALUE    | VOLTAGE | TOLERANCE   | PACK_TYPE   | MATERIAL   | PART_NUMBER                  = STANDARD        | LIFECYCLE          | PART_NUMBER                  | JEDEC_TYPE                 | VALUE    | RATED_VOLTAGE | TOL         | CLASS      | DESCRIPTION                                            | COMPONENT_TYPE | LEAD_LENGTH | DFM_EXCLUSION | DAY        ;
{========================================================================================}
 '100UF'  | '25V'   | '20%'       | 'RDLLF'     | 'ALUM'     | 'TMP_QCC71004MZ65'(!)        = 'End of Design' | 'Comp-Release Qty' | 'CC71004MZ65'                |'EC71_248_304S'| '100UF'  | '25V'         | '20%'       | 'DISCRETE' | 'CAP ELEC 100U 25V(+-20%,105C,6.3*7.7)'                | 'SMT'          | ''          | ''            | ''        
 '100UF'  | '25V'   | '20%'       | 'RDLLF'     | 'EMPTY'    | 'TMP_QCC71004MZ65'(!)        = 'End of Design' | 'Comp-Release Qty' | 'CC71004MZ65'                |'EC71_248_304S'| '100UF'  | '25V'         | '20%'       | 'IO'       | 'CAP ELEC 100U 25V(+-20%,105C,6.3*7.7)'                | 'SMT'          | ''          | ''            | ''        
 '33UF'   | '8V'    | '20%'       | 'RDLLF'     | 'C_TAN'    | 'TMP_QCH6330MM682'(!)        = 'End of Design' | 'Comp-Approve'     | 'CH6330MM682'                |'TAJ_B2'| '33UF'   | '8V'          | '20%'       | 'DISCRETE' | 'CAP CHIP 33UF 8V +-20%,POSCAP(3528)'                  | 'SMT'          | ''          | ''            | ''        
 '33UF'   | '8V'    | '20%'       | 'RDLLF'     | 'EMPTY'    | 'TMP_QCH6330MM682'(!)        = 'End of Design' | 'Comp-Approve'     | 'CH6330MM682'                |'TAJ_B2'| '33UF'   | '8V'          | '20%'       | 'IO'       | 'CAP CHIP 33UF 8V +-20%,POSCAP(3528)'                  | 'SMT'          | ''          | ''            | ''        
 '4.7UF'  | '10V'   | '20%'       | 'RDLLF'     | 'C_TAN'    | 'TMP-C_S50_YAOHSUN_1213_1'(!) = ''              | ''                 | 'TMP-C_S50_YAOHSUN_1213_1'   |'TAJ_A'| '4.7UF'  | '10V'         | '20%'       | 'DISCRETE' | 'CAP CHIP 4.7U,10V(+-20%,TAN,3216)'                    | 'SMT'          | ''          | ''            | ''        
 '4.7UF'  | '10V'   | '20%'       | 'RDLLF'     | 'EMPTY'    | 'TMP-C_S50_YAOHSUN_1213_1'(!) = ''              | ''                 | 'TMP-C_S50_YAOHSUN_1213_1'   |'TAJ_A'| '4.7UF'  | '10V'         | '20%'       | 'IO'       | 'CAP CHIP 4.7U,10V(+-20%,TAN,3216)'                    | 'SMT'          | ''          | ''            | ''        
 '47UF'   | '25V'   | '20%'       | 'RDLLF'     | 'ALUM'     | 'TMP_QCC64704MZ59'(!)        = 'End of Design' | 'Comp-Approve'     | 'CC64704MZ59'                |'EC87_248_237S'| '47UF'   | '25V'         | '20%'       | 'DISCRETE' | 'CAP ELEC SMD 47U 25V(+-20%,105C,6.3*6.0)'             | 'SMT'          | ''          | ''            | ''        
 '47UF'   | '25V'   | '20%'       | 'RDLLF'     | 'EMPTY'    | 'TMP_QCC64704MZ59'(!)        = 'End of Design' | 'Comp-Approve'     | 'CC64704MZ59'                |'EC87_248_237S'| '47UF'   | '25V'         | '20%'       | 'IO'       | 'CAP ELEC SMD 47U 25V(+-20%,105C,6.3*6.0)'             | 'SMT'          | ''          | ''            | ''        
 '330UF'  | '2.5V'  | '20%'       | 'RDLLF'     | 'C_TAN'    | 'TMP_QCH733LM8821'(!)        = ''              | ''                 | 'CH733LM8821'                | 'TAJ_D'                    | '330UF'  | '2.5V'        | '20%'       | 'DISCRETE' | 'CAP CHIP 330UF 2.5V(+-20%,ESR=7,7343)'                | 'SMT'          | ''          | ''            | ''        
 '330UF'  | '2.5V'  | '20%'       | 'RDLLF'     | 'EMPTY'    | 'TMP_QCH733LM8821'(!)        = ''              | ''                 | 'CH733LM8821'                | 'TAJ_D'                    | '330UF'  | '2.5V'        | '20%'       | 'IO'       | 'CAP CHIP 330UF 2.5V(+-20%,ESR=7,7343)'                | 'SMT'          | ''          | ''            | ''        
 '820UF'  | '2.5V'  | '20%'       | 'RDLLF'     | 'OSCON'    | 'TMP_QCC7820JMD01'(!)        = ''              | ''                 | 'CC7820JMD01'                |'EC98_248_315'| '820UF'  | '2.5V'        | '20%'       | 'DISCRETE' | 'CAP OSCON DIP 820U 2.5V(+-20%,6.3*8)'                 | 'DIP'          | ''          | ''            | ''        
 '820UF'  | '2.5V'  | '20%'       | 'RDLLF'     | 'EMPTY'    | 'TMP_QCC7820JMD01'(!)        = ''              | ''                 | 'CC7820JMD01'                |'EC98_248_315'| '820UF'  | '2.5V'        | '20%'       | 'IO'       | 'CAP OSCON DIP 820U 2.5V(+-20%,6.3*8)'                 | 'DIP'          | ''          | ''            | ''        
 '560UF'  | '4V'    | '20%'       | 'RDLLF'     | 'OSCON'    | 'TMP_QCC7560IMD05'(!)        = 'End of Design' | 'P/N Release'      | 'CC7560IMD05'                |'EC98_248_315'| '560UF'  | '4V'          | '20%'       | 'DISCRETE' | 'CAP OSCON DIP 560U 4V(+-20%,6.3*8)'                   | 'DIP'          | ''          | ''            | ''        
 '560UF'  | '4V'    | '20%'       | 'RDLLF'     | 'EMPTY'    | 'TMP_QCC7560IMD05'(!)        = 'End of Design' | 'P/N Release'      | 'CC7560IMD05'                |'EC98_248_315'| '560UF'  | '4V'          | '20%'       | 'IO'       | 'CAP OSCON DIP 560U 4V(+-20%,6.3*8)'                   | 'DIP'          | ''          | ''            | ''        
 '470UF'  | '6.3V'  | '20%'       | 'RDLLF'     | 'OSCON'    | 'TMP_QCC74701MD03'(!)        = 'End of Design' | 'Comp-Approve'     | 'CC74701MD03'                |'EC98_248_315'| '470UF'  | '6.3V'        | '20%'       | 'DISCRETE' | 'CAP OSCON DIP 470U 6.3V(+-20%,6.3*8)'                 | 'DIP'          | ''          | ''            | ''        
 '470UF'  | '6.3V'  | '20%'       | 'RDLLF'     | 'EMPTY'    | 'TMP_QCC74701MD03'(!)        = 'End of Design' | 'Comp-Approve'     | 'CC74701MD03'                |'EC98_248_315'| '470UF'  | '6.3V'        | '20%'       | 'IO'       | 'CAP OSCON DIP 470U 6.3V(+-20%,6.3*8)'                 | 'DIP'          | ''          | ''            | ''        
 '560UF'  | '6.3V'  | '20%'       | 'RDLLF'     | 'OSCON'    | 'TMP_QCC75601MD01'(!)        = ''              | ''                 | 'CC75601MD01'                |'EC2-5_6-8_9-5'| '560UF'  | '6.3V'        | '20%'       | 'DISCRETE' | 'CAP OSCON DIP 560U 6.3V(+-20%,6.3*9)'                 | 'DIP'          | ''          | ''            | ''        
 '560UF'  | '6.3V'  | '20%'       | 'RDLLF'     | 'EMPTY'    | 'TMP_QCC75601MD01'(!)        = ''              | ''                 | 'CC75601MD01'                |'EC2-5_6-8_9-5'| '560UF'  | '6.3V'        | '20%'       | 'IO'       | 'CAP OSCON DIP 560U 6.3V(+-20%,6.3*9)'                 | 'DIP'          | ''          | ''            | ''        
 '220UF'  | '16V'   | '20%'       | 'RDLLF'     | 'ALUM'     | 'TMP_QCC72203MD01'(!)        = ''              | ''                 | 'CC72203MD01'                |'EC138_315_315'| '220UF'  | '16V'         | '20%'       | 'DISCRETE' | 'CAP ELEC DIP 220U 16V(+-20%,8*8)'                     | 'DIP'          | ''          | ''            | ''        
 '220UF'  | '16V'   | '20%'       | 'RDLLF'     | 'EMPTY'    | 'TMP_QCC72203MD01'(!)        = ''              | ''                 | 'CC72203MD01'                |'EC138_315_315'| '220UF'  | '16V'         | '20%'       | 'IO'       | 'CAP ELEC DIP 220U 16V(+-20%,8*8)'                     | 'DIP'          | ''          | ''            | ''        
 '330UF'  | '2.5V'  | '20%'       | 'RDLLF'     | 'ALUM'     | 'TMP_QCH733LM8812'(!)        = ''              | ''                 | 'CH733LM8812'                |'TAJ_D2E'| '330UF'  | '2.5V'        | '20%'       | 'DISCRETE' | 'CAP CHIP330U2.5V(20%,ESR9,7343,H1.8)EP'               | 'DIP'          | ''          | ''            | ''        
 '330UF'  | '2.5V'  | '20%'       | 'RDLLF'     | 'EMPTY'    | 'TMP_QCH733LM8812'(!)        = ''              | ''                 | 'CH733LM8812'                |'TAJ_D2E'| '330UF'  | '2.5V'        | '20%'       | 'IO'       | 'CAP CHIP330U2.5V(20%,ESR9,7343,H1.8)EP'               | 'DIP'          | ''          | ''            | ''        
 '270UF'  | '16V'   | '20%'       | 'RDLLF'     | 'OSCON'    | 'TMP_QCC72703MD03'(!)        = ''              | ''                 | 'CC72703MD03'                |'EC138_315_354A'| '270UF'  | '16V'         | '20%'       | 'DISCRETE' | 'CAP OSCON DIP 270U 16V(+-20%,8*9)'                    | 'DIP'          | ''          | ''            | ''        
 '270UF'  | '16V'   | '20%'       | 'RDLLF'     | 'EMPTY'    | 'TMP_QCC72703MD03'(!)        = ''              | ''                 | 'CC72703MD03'                |'EC138_315_354A'| '270UF'  | '16V'         | '20%'       | 'IO'       | 'CAP OSCON DIP 270U 16V(+-20%,8*9)'                    | 'DIP'          | ''          | ''            | ''        
 '270UF'  | '16V'   | '20%'       | 'RDLLF'     | 'ALUM'     | 'TMP_QCC72703MD36'(!)        = 'End of Design' | 'Comp-Approve'     | 'CC72703MD36'                |'EC138_315_512'| '270UF'  | '16V'         | '20%'       | 'DISCRETE' | 'CAP ELEC DIP 270U 16V(+-20%,8*12)EP'                  | 'DIP'          | ''          | ''            | ''        
 '270UF'  | '16V'   | '20%'       | 'RDLLF'     | 'EMPTY'    | 'TMP_QCC72703MD36'(!)        = 'End of Design' | 'Comp-Approve'     | 'CC72703MD36'                |'EC138_315_512'| '270UF'  | '16V'         | '20%'       | 'IO'       | 'CAP ELEC DIP 270U 16V(+-20%,8*12)EP'                  | 'DIP'          | ''          | ''            | ''        
 '220UF'  | '16V'   | '20%'       | 'RDLLF'     | 'ALUM'     | 'TMP_QCC72203MZ02'(!)        = 'End of Design' | 'Comp-Approve'     | 'CC72203MZ02'                |'EC178_394_304S'| '220UF'  | '16V'         | '20%'       | 'DISCRETE' | 'CAP ELEC SMD 220U 16V(20%,105C,10*8)'                 | 'SMD'          | ''          | ''            | ''        
 '220UF'  | '16V'   | '20%'       | 'RDLLF'     | 'EMPTY'    | 'TMP_QCC72203MZ02'(!)        = 'End of Design' | 'Comp-Approve'     | 'CC72203MZ02'                |'EC178_394_304S'| '220UF'  | '16V'         | '20%'       | 'IO'       | 'CAP ELEC SMD 220U 16V(20%,105C,10*8)'                 | 'SMD'          | ''          | ''            | ''        
 '100UF'  | '16V'   | '20%'       | 'RDLLF'     | 'OSCON'    | 'TMP_QCC71003MD02'(!)        = ''              | ''                 | 'CC71003MD02'                |'EC2-5_6-8_6'| '100UF'  | '16V'         | '20%'       | 'DISCRETE' | 'CAP OSCON DIP 100U 16V(20%,105C,6.3*6)'               | 'DIP'          | ''          | ''            | ''        
 '100UF'  | '16V'   | '20%'       | 'RDLLF'     | 'EMPTY'    | 'TMP_QCC71003MD02'(!)        = ''              | ''                 | 'CC71003MD02'                |'EC2-5_6-8_6'| '100UF'  | '16V'         | '20%'       | 'IO'       | 'CAP OSCON DIP 100U 16V(20%,105C,6.3*6)'               | 'DIP'          | ''          | ''            | ''        
 '100UF'  | '16V'   | '20%'       | 'RDLLF_SEL' | 'OSCON'    | 'CC71003MD02'(!)             = ''              | ''                 | 'CC71003MD02'                |'G_EC2-5_6-8_6'| '100UF'  | '16V'         | '20%'       | 'DISCRETE' | 'CAP OSCON DIP 100U 16V(20%,105C,6.3*6)'               | 'DIP'          | ''          | ''            | ''        
 '100UF'  | '16V'   | '20%'       | 'RDLLF_SEL' | 'EMPTY'    | 'CC71003MD02'(!)             = ''              | ''                 | 'CC71003MD02'                |'G_EC2-5_6-8_6'| '100UF'  | '16V'         | '20%'       | 'IO'       | 'CAP OSCON DIP 100U 16V(20%,105C,6.3*6)'               | 'DIP'          | ''          | ''            | ''        
 '330UF'  | '16V'   | '20%'       | 'RDLLF'     | 'ALUM'     | 'TMP_QCC73303MD18'(!)        = 'End of Design' | 'End of Life'      | 'CC73303MD18'                |'EC138_315_453_EOL'| '330UF'  | '16V'         | '20%'       | 'DISCRETE' | 'CAP ELEC DIP 330U 16V +-20% 105C 8*11.5'              | 'DIP'          | ''          | ''            | ''        
 '330UF'  | '16V'   | '20%'       | 'RDLLF'     | 'EMPTY'    | 'TMP_QCC73303MD18'(!)        = 'End of Design' | 'End of Life'      | 'CC73303MD18'                |'EC138_315_453_EOL'| '330UF'  | '16V'         | '20%'       | 'IO'       | 'CAP ELEC DIP 330U 16V +-20% 105C 8*11.5'              | 'DIP'          | ''          | ''            | ''        
 '220UF'  | '16V'   | '20%'       | 'RDLLF'     | 'ALUM'     | 'TMP_QCC72203MD38'(!)        = 'End of Design' | 'End of Life'      | 'CC72203MD38'                |'EC98_248_433_EOL'| '220UF'  | '16V'         | '20%'       | 'DISCRETE' | 'CAP ELEC DIP 220U 16V(20%,105C,6.3*11)'               | 'DIP'          | ''          | ''            | ''        
 '220UF'  | '16V'   | '20%'       | 'RDLLF'     | 'EMPTY'    | 'TMP_QCC72203MD38'(!)        = 'End of Design' | 'End of Life'      | 'CC72203MD38'                |'EC98_248_433_EOL'| '220UF'  | '16V'         | '20%'       | 'IO'       | 'CAP ELEC DIP 220U 16V(20%,105C,6.3*11)'               | 'DIP'          | ''          | ''            | ''        
 '470UF'  | '10V'   | '20%'       | 'RDLLF'     | 'ALUM'     | 'TMP_QCC74702MDC6'(!)        = ''              | ''                 | 'CC74702MDC6'                |'EC98_248_433'| '470UF'  | '10V'         | '20%'       | 'DISCRETE' | 'CAP ELEC DIP 470U 10V(20%,85C,6.3*11)'                | 'DIP'          | ''          | ''            | ''        
 '470UF'  | '10V'   | '20%'       | 'RDLLF'     | 'EMPTY'    | 'TMP_QCC74702MDC6'(!)        = ''              | ''                 | 'CC74702MDC6'                |'EC98_248_433'| '470UF'  | '10V'         | '20%'       | 'IO'       | 'CAP ELEC DIP 470U 10V(20%,85C,6.3*11)'                | 'DIP'          | ''          | ''            | ''        
 '1000UF' | '6.3V'  | '20%'       | 'RDLLF'     | 'ALUM'     | 'TMP_QCC81001MD00'(!)        = ''              | ''                 | 'CC81001MD00'                |'EC138_315_453'| '1000UF' | '6.3V'        | '20%'       | 'DISCRETE' | 'CAP ELEC 1000U 6.3V(20%,8*11.5)'                      | 'DIP'          | ''          | ''            | ''        
 '1000UF' | '6.3V'  | '20%'       | 'RDLLF'     | 'EMPTY'    | 'TMP_QCC81001MD00'(!)        = ''              | ''                 | 'CC81001MD00'                |'EC138_315_453'| '1000UF' | '6.3V'        | '20%'       | 'IO'       | 'CAP ELEC 1000U 6.3V(20%,8*11.5)'                      | 'DIP'          | ''          | ''            | ''        
 '47UF'   | '35V'   | '20%'       | 'RDLLF'     | 'ALUM'     | 'TMP_QCC64705MZ00'(!)        = ''              | ''                 | 'CC64705MZ00'                |'EC181_394_496S'| '47UF'   | '35V'         | '20%'       | 'DISCRETE' | 'CAP OSCON 47U 35V(20%,ESR30,10*12.6)SMD'              | 'SMD'          | ''          | ''            | ''        
 '47UF'   | '35V'   | '20%'       | 'RDLLF'     | 'EMPTY'    | 'TMP_QCC64705MZ00'(!)        = ''              | ''                 | 'CC64705MZ00'                |'EC181_394_496S'| '47UF'   | '35V'         | '20%'       | 'IO'       | 'CAP OSCON 47U 35V(20%,ESR30,10*12.6)SMD'              | 'SMD'          | ''          | ''            | ''        
 '560UF'  | '2.5V'  | '20%'       | 'RDLLF'     | 'ALUM'     | 'TMP-C_E07_KC_1112_1'(!)     = ''              | ''                 | 'TMP-C_E07_KC_1112_1'        |'EC78_197_315'| '560UF'  | '2.5V'        | '20%'       | 'DISCRETE' | 'CAP OSCON DIP 560U 2.5V(+-20%,5*8)'                   | 'DIP'          | ''          | ''            | ''        
 '560UF'  | '2.5V'  | '20%'       | 'RDLLF'     | 'EMPTY'    | 'TMP-C_E07_KC_1112_1'(!)     = ''              | ''                 | 'TMP-C_E07_KC_1112_1'        |'EC78_197_315'| '560UF'  | '2.5V'        | '20%'       | 'IO'       | 'CAP OSCON DIP 560U 2.5V(+-20%,5*8)'                   | 'DIP'          | ''          | ''            | ''        
 '330UF'  | '2V'    | '20%'       | 'RDLLF'     | 'C_TAN'    | 'TMP_QCH733RM8831'(!)        = ''              | ''                 | 'CH733RM8831'                | 'TAJ_DXA'                  | '330UF'  | '2V'          | '20%'       | 'DISCRETE' | 'CAP 330U 2V(20%,ESR=6,7343,H1.9)'                     | 'SMT'          | ''          | ''            | ''        
 '330UF'  | '2V'    | '20%'       | 'RDLLF'     | 'EMPTY'    | 'TMP_QCH733RM8831'(!)        = ''              | ''                 | 'CH733RM8831'                | 'TAJ_DXA'                  | '330UF'  | '2V'          | '20%'       | 'IO'       | 'CAP 330U 2V(20%,ESR=6,7343,H1.9)'                     | 'SMT'          | ''          | ''            | ''        
 '330UF'  | '6.3V'  | '20%'       | 'RDLLF'     | 'OSCON'    | 'TMP_QCC73301MZC1'(!)        = 'End of Design' | 'Comp-Approve'     | 'CC73301MZC1'                |'EC83_248_225S'| '330UF'  | '6.3V'        | '20%'       | 'DISCRETE' | 'CAP OSCON 330U 6.3V(20%,105C,6.3*5.9)SMD'             | 'SMT'          | ''          | ''            | ''        
 '330UF'  | '6.3V'  | '20%'       | 'RDLLF'     | 'EMPTY'    | 'TMP_QCC73301MZC1'(!)        = 'End of Design' | 'Comp-Approve'     | 'CC73301MZC1'                |'EC83_248_225S'| '330UF'  | '6.3V'        | '20%'       | 'IO'       | 'CAP OSCON 330U 6.3V(20%,105C,6.3*5.9)SMD'             | 'SMT'          | ''          | ''            | ''        
 '680UF'  | '2.5V'  | '20%'       | 'RDLLF'     | 'C_TAN'    | 'TMP_QCH768LM8801'(!)        = 'End of Design' | 'Comp-Approve'     | 'CH768LM8801'                |'TAJ_D3'| '680UF'  | '2.5V'        | '20%'       | 'DISCRETE' | 'CAP CHIP 680U 2.5V (20%,ESR6,7343,H2.8)'              | 'SMT'          | ''          | ''            | ''        
 '680UF'  | '2.5V'  | '20%'       | 'RDLLF'     | 'EMPTY'    | 'TMP_QCH768LM8801'(!)        = 'End of Design' | 'Comp-Approve'     | 'CH768LM8801'                |'TAJ_D3'| '680UF'  | '2.5V'        | '20%'       | 'IO'       | 'CAP CHIP 680U 2.5V (20%,ESR6,7343,H2.8)'              | 'SMT'          | ''          | ''            | ''        
 '180UF'  | '4V'    | '20%'       | 'RDLLF'     | 'C_TAN'    | 'TMP_QCH718KM8800'(!)        = 'End of Design' | 'Comp-Approve'     | 'CH718KM8800'                |'TAJ_UE'| '180UF'  | '4V'          | '20%'       | 'DISCRETE' | 'CAP CHIP 180UF 4V(20%,ESR0.012,7343)H4.2'             | 'SMT'          | ''          | ''            | ''        
 '180UF'  | '4V'    | '20%'       | 'RDLLF'     | 'EMPTY'    | 'TMP_QCH718KM8800'(!)        = 'End of Design' | 'Comp-Approve'     | 'CH718KM8800'                |'TAJ_UE'| '180UF'  | '4V'          | '20%'       | 'IO'       | 'CAP CHIP 180UF 4V(20%,ESR0.012,7343)H4.2'             | 'SMT'          | ''          | ''            | ''        
 '330UF'  | '6.3V'  | '20%'       | 'RDLLF'     | 'C_TAN'    | 'TMP_QCH7331MT800'(!)        = 'End of Design' | 'Comp-Approve'     | 'CH7331MT800'                |'TAJ_D3'| '330UF'  | '6.3V'        | '20%'       | 'DISCRETE' | 'CAP CHIP 330U,6.3V(20%,ESR9,TANT,7343)HF'             | 'DIP'          | ''          | ''            | ''        
 '330UF'  | '6.3V'  | '20%'       | 'RDLLF'     | 'EMPTY'    | 'TMP_QCH7331MT800'(!)        = 'End of Design' | 'Comp-Approve'     | 'CH7331MT800'                |'TAJ_D3'| '330UF'  | '6.3V'        | '20%'       | 'IO'       | 'CAP CHIP 330U,6.3V(20%,ESR9,TANT,7343)HF'             | 'DIP'          | ''          | ''            | ''        
 '560UF'  | '6.3V'  | '20%'       | 'RDLLF_SEL' | 'OSCON'    | 'CC75601MD05'(!)             = ''              | ''                 | 'CC75601MD05'                |'G_EC98_248_354'| '560UF'  | '6.3V'        | '20%'       | 'DISCRETE' | 'CAPOSCON DIP 560U6.3V(+-20%,6.3*9)SELASS'             | 'DIP'          | ''          | ''            | ''        
 '560UF'  | '6.3V'  | '20%'       | 'RDLLF_SEL' | 'EMPTY'    | 'CC75601MD05'(!)             = ''              | ''                 | 'CC75601MD05'                |'G_EC98_248_354'| '560UF'  | '6.3V'        | '20%'       | 'IO'       | 'CAPOSCON DIP 560U6.3V(+-20%,6.3*9)SELASS'             | 'DIP'          | ''          | ''            | ''        
 '270UF'  | '16V'   | '20%'       | 'RDLLF_SEL' | 'OSCON'    | 'CC72703MD12'(!)             = ''              | ''                 | 'CC72703MD12'                |'G_EC138_315_354A'| '270UF'  | '16V'         | '20%'       | 'DISCRETE' | 'CAP OSCON DIP 270U 16V(+-20%,8*9)SEL-ASS'             | 'DIP'          | ''          | ''            | ''        
 '270UF'  | '16V'   | '20%'       | 'RDLLF_SEL' | 'EMPTY'    | 'CC72703MD12'(!)             = ''              | ''                 | 'CC72703MD12'                |'G_EC138_315_354A'| '270UF'  | '16V'         | '20%'       | 'IO'       | 'CAP OSCON DIP 270U 16V(+-20%,8*9)SEL-ASS'             | 'DIP'          | ''          | ''            | ''        
 '150UF'  | '10V'   | '20%'       | 'RDLLF'     | 'C_TAN'    | 'CH7152MT829'(!)             = 'End of Design' | 'Comp-Approve'     | 'CH7152MT829'                |'TAJ_D'| '150UF'  | '10V'         | '20%'       | 'DISCRETE' | 'CAP CHIP 150U,10V(+-20%,TAN,7343)H2.8'                | 'SMT'          | ''          | ''            | ''        
 '150UF'  | '10V'   | '20%'       | 'RDLLF'     | 'EMPTY'    | 'CH7152MT829'(!)             = 'End of Design' | 'Comp-Approve'     | 'CH7152MT829'                |'TAJ_D'| '150UF'  | '10V'         | '20%'       | 'IO'       | 'CAP CHIP 150U,10V(+-20%,TAN,7343)H2.8'                | 'SMT'          | ''          | ''            | ''        
 '560UF'  | '2.5V'  | '20%'       | 'RDLLF_SEL' | 'OSCON'    | 'CC7560JMD03'(!)             = ''              | ''                 | 'CC7560JMD03'                |'G_EC78_197_355'| '560UF'  | '2.5V'        | '20%'       | 'DISCRETE' | 'CAP OSCON DIP 560U 2.5V(20%,105C,5*8)'                | 'DIP'          | ''          | ''            | ''        
 '560UF'  | '2.5V'  | '20%'       | 'RDLLF_SEL' | 'EMPTY'    | 'CC7560JMD03'(!)             = ''              | ''                 | 'CC7560JMD03'                |'G_EC78_197_355'| '560UF'  | '2.5V'        | '20%'       | 'IO'       | 'CAP OSCON DIP 560U 2.5V(20%,105C,5*8)'                | 'DIP'          | ''          | ''            | ''        
 '470UF'  | '2.5V'  | '20%'       | 'RDLLF'     | 'C_TAN'    | 'CH747LM8861'(!)             = 'End of Design' | 'Comp-Approve'     | 'CH747LM8861'                |'TAJ_D3L'| '470UF'  | '2.5V'        | '20%'       | 'DISCRETE' | 'CAP CHIP 470U 2.5V (20%,ESR6,7343,H2.8)'              | 'SMT'          | ''          | ''            | ''        
 '470UF'  | '2.5V'  | '20%'       | 'RDLLF'     | 'EMPTY'    | 'CH747LM8861'(!)             = 'End of Design' | 'Comp-Approve'     | 'CH747LM8861'                |'TAJ_D3L'| '470UF'  | '2.5V'        | '20%'       | 'IO'       | 'CAP CHIP 470U 2.5V (20%,ESR6,7343,H2.8)'              | 'SMT'          | ''          | ''            | ''        
 '22UF'   | '16V'   | '10%'       | 'RDLLF'     | 'C_TAN'    | 'CH6223KT600'(!)             = ''              | ''                 | 'CH6223KT600'                |'TAJ_B2'| '22UF'   | '16V'         | '10%'       | 'DISCRETE' | 'CAP CHIP 22UF 16V(+-10%,TAN,3528)H1.9'                | 'SMT'          | ''          | ''            | ''        
 '22UF'   | '16V'   | '10%'       | 'RDLLF'     | 'EMPTY'    | 'CH6223KT600'(!)             = ''              | ''                 | 'CH6223KT600'                |'TAJ_B2'| '22UF'   | '16V'         | '10%'       | 'IO'       | 'CAP CHIP 22UF 16V(+-10%,TAN,3528)H1.9'                | 'SMT'          | ''          | ''            | ''        
 '220UF'  | '10V'   | '20%'       | 'RDLLF'     | 'C_TAN'    | 'CH7222M8808'(!)             = 'End of Design' | 'Comp-Approve'     | 'CH7222M8808'                |'TAJ_D3'| '220UF'  | '10V'         | '20%'       | 'DISCRETE' | 'CAP CHIP 220U 10V(20%,ESR25,7343)H2.8'                | 'SMT'          | ''          | ''            | ''        
 '220UF'  | '10V'   | '20%'       | 'RDLLF'     | 'EMPTY'    | 'CH7222M8808'(!)             = 'End of Design' | 'Comp-Approve'     | 'CH7222M8808'                |'TAJ_D3'| '220UF'  | '10V'         | '20%'       | 'IO'       | 'CAP CHIP 220U 10V(20%,ESR25,7343)H2.8'                | 'SMT'          | ''          | ''            | ''        
 '68UF'   | '16V'   | '20%'       | 'RDLLF'     | 'C_POSCAP' | 'CH6683M8802'(!)             = 'End of Design' | 'Comp-Approve'     | 'CH6683M8802'                |'TAJ_D2'| '68UF'   | '16V'         | '20%'       | 'DISCRETE' | 'CAP CHIP 68U 16V( +-20%,ESR50,7343,H1.9)'             | 'SMT'          | ''          | ''            | '20100720'
 '68UF'   | '16V'   | '20%'       | 'RDLLF'     | 'EMPTY'    | 'CH6683M8802'(!)             = 'End of Design' | 'Comp-Approve'     | 'CH6683M8802'                |'TAJ_D2'| '68UF'   | '16V'         | '20%'       | 'IO'       | 'CAP CHIP 68U 16V( +-20%,ESR50,7343,H1.9)'             | 'SMT'          | ''          | ''            | '20100720'
 '470UF'  | '2.5V'  | '20%'       | 'RDLLF'     | 'C_TAN'    | 'CH747LM8807'(!)             = 'End of Design' | 'Comp-Approve'     | 'CH747LM8807'                |'TAJ_D2'| '470UF'  | '2.5V'        | '20%'       | 'DISCRETE' | 'CAP CHIP 470U 2.5V(+-20%,ESR6,7343,H1.9)'             | 'SMT'          | ''          | ''            | '20100924'
 '470UF'  | '2.5V'  | '20%'       | 'RDLLF'     | 'EMPTY'    | 'CH747LM8807'(!)             = 'End of Design' | 'Comp-Approve'     | 'CH747LM8807'                |'TAJ_D2'| '470UF'  | '2.5V'        | '20%'       | 'IO'       | 'CAP CHIP 470U 2.5V(+-20%,ESR6,7343,H1.9)'             | 'SMT'          | ''          | ''            | '20100924'
 '330UF'  | '2.5V'  | '20%'       | 'RDLLF'     | 'C_TAN'    | 'CH733LM8880'(!)             = ''              | ''                 | 'CH733LM8880'                | 'TAJ_D'                    | '330UF'  | '2.5V'        | '20%'       | 'DISCRETE' | 'CAP CHIP330UF2.5V(+-20%,ESR=6,7343,H2.8)'             | 'SMT'          | ''          | ''            | '20101004'
 '330UF'  | '2.5V'  | '20%'       | 'RDLLF'     | 'EMPTY'    | 'CH733LM8880'(!)             = ''              | ''                 | 'CH733LM8880'                | 'TAJ_D'                    | '330UF'  | '2.5V'        | '20%'       | 'IO'       | 'CAP CHIP330UF2.5V(+-20%,ESR=6,7343,H2.8)'             | 'SMT'          | ''          | ''            | '20101004'
 '470UF'  | '10V'   | '20%'       | 'RDLLF'     | 'C_TAN'    | 'CH7472MT801'(!)             = ''              | ''                 | 'CH7472MT801'                | 'TAJ_DA'                   | '470UF'  | '10V'         | '20%'       | 'DISCRETE' | 'CAP CHIP 470U 10V(20%,ESR=500M,7343)H4.1'             | 'SMT'          | ''          | ''            | '20101004'
 '470UF'  | '10V'   | '20%'       | 'RDLLF'     | 'EMPTY'    | 'CH7472MT801'(!)             = ''              | ''                 | 'CH7472MT801'                | 'TAJ_DA'                   | '470UF'  | '10V'         | '20%'       | 'IO'       | 'CAP CHIP 470U 10V(20%,ESR=500M,7343)H4.1'             | 'SMT'          | ''          | ''            | '20101004'
 '560UF'  | '6.3V'  | '20%'       | 'RDLLF'     | 'OSCON'    | 'CC75601MD02'(!)             = 'End of Design' | 'End of Life'      | 'CC75601MD02'                |'EC98_248_315_EOL'| '560UF'  | '6.3V'        | '20%'       | 'DISCRETE' | 'CAP OSCON DIP 560U 6.3V(+-20%,6.3*8)'                 | 'DIP'          | ''          | ''            | '20101005'
 '560UF'  | '6.3V'  | '20%'       | 'RDLLF'     | 'EMPTY'    | 'CC75601MD02'(!)             = 'End of Design' | 'End of Life'      | 'CC75601MD02'                |'EC98_248_315_EOL'| '560UF'  | '6.3V'        | '20%'       | 'IO'       | 'CAP OSCON DIP 560U 6.3V(+-20%,6.3*8)'                 | 'DIP'          | ''          | ''            | '20101005'
 '470UF'  | '2V'    | '20%'       | 'RDLLF'     | 'C_POSCAP' | 'CH747RM8811'(!)             = ''              | ''                 | 'CH747RM8811'                | 'TAJ_DXC'                  | '470UF'  | '2V'          | '20%'       | 'DISCRETE' | 'CAP CHIP 470U 2V(+-20% ESR=3,7343)H1.9'               | 'SMT'          | ''          | ''            | '20101116'
 '470UF'  | '2V'    | '20%'       | 'RDLLF'     | 'EMPTY'    | 'CH747RM8811'(!)             = ''              | ''                 | 'CH747RM8811'                | 'TAJ_DXC'                  | '470UF'  | '2V'          | '20%'       | 'IO'       | 'CAP CHIP 470U 2V(+-20% ESR=3,7343)H1.9'               | 'SMT'          | ''          | ''            | '20101116'
 '220UF'  | '2V'    | '20%'       | 'RDLLF_SEL' | 'C_TAN'    | 'CH722RM8809'(!)             = ''              | ''                 | 'CH722RM8809'                | 'TAJ_D2E'                  | '220UF'  | '2V'          | '20%'       | 'DISCRETE' | 'CAPCHIP220U2V(20%,ESR=6,H1.8,7343)SELASS'             | 'SMT'          | ''          | ''            | '20101116'
 '220UF'  | '2V'    | '20%'       | 'RDLLF_SEL' | 'EMPTY'    | 'CH722RM8809'(!)             = ''              | ''                 | 'CH722RM8809'                | 'TAJ_D2E'                  | '220UF'  | '2V'          | '20%'       | 'IO'       | 'CAPCHIP220U2V(20%,ESR=6,H1.8,7343)SELASS'             | 'SMT'          | ''          | ''            | '20101116'
 '270UF'  | '10V'   | '20%'       | 'RDLLF_SEL' | 'OSCON'    | 'TMP_T2B_KUOCHAN_1117_1'(!)  = ''              | ''                 | 'SP_TMP_T2B_KUOCHAN_1117_1'  |'G_EC138_315_276'| '270UF'  | '10V'         | '20%'       | 'DISCRETE' | 'CAP OSCON 270U 10V(20%,105C,8*7) SELASS'              | 'DIP'          | ''          | ''            | '20101118'
 '270UF'  | '10V'   | '20%'       | 'RDLLF_SEL' | 'EMPTY'    | 'TMP_T2B_KUOCHAN_1117_1'(!)  = ''              | ''                 | 'SP_TMP_T2B_KUOCHAN_1117_1'  |'G_EC138_315_276'| '270UF'  | '10V'         | '20%'       | 'IO'       | 'CAP OSCON 270U 10V(20%,105C,8*7) SELASS'              | 'DIP'          | ''          | ''            | '20101118'
 '220UF'  | '16V'   | '20%'       | 'RDLLF_SEL' | 'OSCON'    | 'TMP_T2B_KUOCHAN_1117_2'(!)  = ''              | ''                 | 'SP_TMP_T2B_KUOCHAN_1117_2'  |'G_EC138_315_276'| '220UF'  | '16V'         | '20%'       | 'DISCRETE' | 'CAP OSCON 220U 16V(20%,105C,8*7) SELASS'              | 'DIP'          | ''          | ''            | '20101118'
 '220UF'  | '16V'   | '20%'       | 'RDLLF_SEL' | 'EMPTY'    | 'TMP_T2B_KUOCHAN_1117_2'(!)  = ''              | ''                 | 'SP_TMP_T2B_KUOCHAN_1117_2'  |'G_EC138_315_276'| '220UF'  | '16V'         | '20%'       | 'IO'       | 'CAP OSCON 220U 16V(20%,105C,8*7) SELASS'              | 'DIP'          | ''          | ''            | '20101118'
 '560UF'  | '2.5V'  | '20%'       | 'RDLLF'     | 'OSCON'    | 'CC7560JMD03'(!)             = ''              | ''                 | 'CC7560JMD03'                |'EC78_197_355'| '560UF'  | '2.5V'        | '20%'       | 'DISCRETE' | 'CAP OSCON DIP 560U 2.5V(20%,105C,5*8)'                | 'DIP'          | ''          | ''            | '20110104'
 '560UF'  | '2.5V'  | '20%'       | 'RDLLF'     | 'EMPTY'    | 'CC7560JMD03'(!)             = ''              | ''                 | 'CC7560JMD03'                |'EC78_197_355'| '560UF'  | '2.5V'        | '20%'       | 'IO'       | 'CAP OSCON DIP 560U 2.5V(20%,105C,5*8)'                | 'DIP'          | ''          | ''            | '20110104'
 '330UF'  | '2V'    | '20%'       | 'RDLLF'     | 'C_TAN'    | 'CH733RM8602'(!)             = 'End of Design' | 'Comp-Approve'     | 'CH733RM8602'                |'TAJ_B2'| '330UF'  | '2V'          | '20%'       | 'DISCRETE' | 'CAPCHIP 330U 2V(20%,ESR13M,3528,H1.9)HF'              | 'SMT'          | ''          | ''            | '20110219'
 '330UF'  | '2V'    | '20%'       | 'RDLLF'     | 'EMPTY'    | 'CH733RM8602'(!)             = 'End of Design' | 'Comp-Approve'     | 'CH733RM8602'                |'TAJ_B2'| '330UF'  | '2V'          | '20%'       | 'IO'       | 'CAPCHIP 330U 2V(20%,ESR13M,3528,H1.9)HF'              | 'SMT'          | ''          | ''            | '20110219'
 '330UF'  | '2.5V'  | '20%'       | 'RDLLF'     | 'C_TAN'    | 'CH733LM8600'(!)             = ''              | ''                 | 'CH733LM8600'                |'TAJ_B2'| '330UF'  | '2.5V'        | '20%'       | 'DISCRETE' | 'CAP CHIP 330U 2.5V(+-20%,ESR35,3528)H1.9'             | 'SMT'          | ''          | ''            | '20110411'
 '330UF'  | '2.5V'  | '20%'       | 'RDLLF'     | 'EMPTY'    | 'CH733LM8600'(!)             = ''              | ''                 | 'CH733LM8600'                |'TAJ_B2'| '330UF'  | '2.5V'        | '20%'       | 'IO'       | 'CAP CHIP 330U 2.5V(+-20%,ESR35,3528)H1.9'             | 'SMT'          | ''          | ''            | '20110411'
 '330UF'  | '2.5V'  | '20%'       | 'RDLLF'     | 'C_TAN'    | 'CH733LM8605'(!)             = 'End of Design' | 'Comp-Approve'     | 'CH733LM8605'                |'TAJ_B2'| '330UF'  | '2.5V'        | '20%'       | 'DISCRETE' | 'CAP CHIP 330U 2.5V(+/-20%.ESR9.3528)H1.9'             | 'SMT'          | ''          | ''            | '20110503'
 '330UF'  | '2.5V'  | '20%'       | 'RDLLF'     | 'EMPTY'    | 'CH733LM8605'(!)             = 'End of Design' | 'Comp-Approve'     | 'CH733LM8605'                |'TAJ_B2'| '330UF'  | '2.5V'        | '20%'       | 'IO'       | 'CAP CHIP 330U 2.5V(+/-20%.ESR9.3528)H1.9'             | 'SMT'          | ''          | ''            | '20110503'
 '390UF'  | '2.5V'  | '20%'       | 'RDLLF'     | 'OSCON'    | 'CC7390JMD00'(!)             = ''              | ''                 | 'CC7390JMD00'                |'EC98_248_237'| '390U'   | '2.5V'        | '20%'       | 'DISCRETE' | 'CAP OSCON 390U 2.5V(20%,105C,6.3*6)ESR10'             | 'DIP'          | ''          | ''            | '20110516'
 '390UF'  | '2.5V'  | '20%'       | 'RDLLF'     | 'EMPTY'    | 'CC7390JMD00'(!)             = ''              | ''                 | 'CC7390JMD00'                |'EC98_248_237'| '390U'   | '2.5V'        | '20%'       | 'IO'       | 'CAP OSCON 390U 2.5V(20%,105C,6.3*6)ESR10'             | 'DIP'          | ''          | ''            | '20110516'
 '220UF'  | '10V'   | '20%'       | 'RDLLF'     | 'OSCON'    | 'CH7222MT804'(!)             = 'End of Design' | 'Comp-Approve'     | 'CH7222MT804'                |'TAJ_D'| '220UF'  | '10V'         | '20%'       | 'DISCRETE' | 'CAP CHIP 220U 10V(+-20%,TAN7343,H2.8)'                | 'SMT'          | ''          | ''            | '20110608'
 '220UF'  | '10V'   | '20%'       | 'RDLLF'     | 'EMPTY'    | 'CH7222MT804'(!)             = 'End of Design' | 'Comp-Approve'     | 'CH7222MT804'                |'TAJ_D'| '220UF'  | '10V'         | '20%'       | 'IO'       | 'CAP CHIP 220U 10V(+-20%,TAN7343,H2.8)'                | 'SMT'          | ''          | ''            | '20110608'
 '470UF'  | '16V'   | '20%'       | 'RDLLF'     | 'OSCON'    | 'CC74703MD05'(!)             = 'End of Design' | 'Comp-Approve'     | 'CC74703MD05'                |'EC197_394_512'| '220UF'  | '16V'         | '20%'       | 'DISCRETE' | 'CAP ELEC 470U 16V(20%,105C,ESR10,10*13)'              | 'DIP'          | ''          | ''            | '20110610'
 '470UF'  | '16V'   | '20%'       | 'RDLLF'     | 'EMPTY'    | 'CC74703MD05'(!)             = 'End of Design' | 'Comp-Approve'     | 'CC74703MD05'                |'EC197_394_512'| '220UF'  | '16V'         | '20%'       | 'IO'       | 'CAP ELEC 470U 16V(20%,105C,ESR10,10*13)'              | 'DIP'          | ''          | ''            | '20110610'
 '100UF'  | '16V'   | '20%'       | 'RDLLF'     | 'OSCON'    | 'CC71003MZ16'(!)             = ''              | ''                 | 'CC71003MZ16'                |'EC83_248_225S'| '100UF'  | '16V'         | '20%'       | 'DISCRETE' | 'CAP OSCON SMD 100U 16V(20%,105C,6.3*5.7)'             | 'SMT'          | ''          | ''            | '20110615'
 '100UF'  | '16V'   | '20%'       | 'RDLLF'     | 'EMPTY'    | 'CC71003MZ16'(!)             = ''              | ''                 | 'CC71003MZ16'                |'EC83_248_225S'| '100UF'  | '16V'         | '20%'       | 'IO'       | 'CAP OSCON SMD 100U 16V(20%,105C,6.3*5.7)'             | 'SMT'          | ''          | ''            | '20110615'
 '180UF'  | '16V'   | '20%'       | 'RDLLF'     | 'ALUM'     | 'CC71803MD01'(!)             = ''              | 'End of Life'      | 'CC71803MD01'                |'EC123_315_473S_EOL'| '180UF'  | '16V'         | '20%'       | 'DISCRETE' | 'CAP ELE SMD 180U 16V(+-20%105C,8*12)'                 | 'SMT'          | ''          | ''            | '20110824'
 '180UF'  | '16V'   | '20%'       | 'RDLLF'     | 'EMPTY'    | 'CC71803MD01'(!)             = ''              | 'End of Life'      | 'CC71803MD01'                |'EC123_315_473S_EOL'| '180UF'  | '16V'         | '20%'       | 'IO'       | 'CAP ELE SMD 180U 16V(+-20%105C,8*12)'                 | 'SMT'          | ''          | ''            | '20110824'
 '150UF'  | '16V'   | '20%'       | 'RDLLF'     | 'ALUM'     | 'CC71503MZ01'(!)             = 'End of Design' | 'Comp-Approve'     | 'CC71503MZ01'                |'EC123_315_304S'| '150UF'  | '16V'         | '20%'       | 'DISCRETE' | 'CAP ELEC SMD 150UF 16V(20%,105C,8*7.7)'               | 'SMT'          | ''          | ''            | '20110824'
 '150UF'  | '16V'   | '20%'       | 'RDLLF'     | 'EMPTY'    | 'CC71503MZ01'(!)             = 'End of Design' | 'Comp-Approve'     | 'CC71503MZ01'                |'EC123_315_304S'| '150UF'  | '16V'         | '20%'       | 'IO'       | 'CAP ELEC SMD 150UF 16V(20%,105C,8*7.7)'               | 'SMT'          | ''          | ''            | '20110824'
 '330UF'  | '6.3V'  | '20%'       | 'RDLLF'     | 'ALUM'     | 'CC73301MZ00'(!)             = ''              | ''                 | 'CC73301MZ00'                |'EC75_248_229SXA'| '330UF'  | '6.3V'        | '20%'       | 'DISCRETE' | 'CAP ELEC SMD 330U,6.3V(20%ESR17,6.3*5.8)'             | 'SMT'          | ''          | ''            | '20111226'
 '330UF'  | '6.3V'  | '20%'       | 'RDLLF'     | 'EMPTY'    | 'CC73301MZ00'(!)             = ''              | ''                 | 'CC73301MZ00'                |'EC75_248_229SXA'| '330UF'  | '6.3V'        | '20%'       | 'IO'       | 'CAP ELEC SMD 330U,6.3V(20%ESR17,6.3*5.8)'             | 'SMT'          | ''          | ''            | '20111226'
 '470UF'  | '10V'   | '20%'       | 'RDLLF'     | 'ALUM'     | 'CC74702MDA0'(!)             = 'End of Design' | 'Comp-Approve'     | 'CC74702MDA0'                |'EC98_248_433'| '470UF'  | '10V'         | '20%'       | 'DISCRETE' | 'CAP ELEC DIP 470U 10V(20%.105C.6*11)'                 | 'DIP'          | ''          | ''            | '20111226'
 '470UF'  | '10V'   | '20%'       | 'RDLLF'     | 'EMPTY'    | 'CC74702MDA0'(!)             = 'End of Design' | 'Comp-Approve'     | 'CC74702MDA0'                |'EC98_248_433'| '470UF'  | '10V'         | '20%'       | 'IO'       | 'CAP ELEC DIP 470U 10V(20%.105C.6*11)'                 | 'DIP'          | ''          | ''            | '20111226'
 '100UF'  | '100V'  | '20%'       | 'RDLLF'     | 'ALUM'     | 'CC71008MD01'(!)             = ''              | ''                 | 'CC71008MD01'                |'EC197_394_787'| '100UF'  | '100V'        | '20%'       | 'DISCRETE' | 'CAP ELEC DIP 100U 100V(20%.105C.10*20)'               | 'DIP'          | ''          | ''            | '20120110'
 '100UF'  | '100V'  | '20%'       | 'RDLLF'     | 'EMPTY'    | 'CC71008MD01'(!)             = ''              | ''                 | 'CC71008MD01'                |'EC197_394_787'| '100UF'  | '100V'        | '20%'       | 'IO'       | 'CAP ELEC DIP 100U 100V(20%.105C.10*20)'               | 'DIP'          | ''          | ''            | '20120110'
 '100UF'  | '100V'  | '20%'       | 'RDLLF_SEL' | 'ALUM'     | 'SP_CC71008MD01'(!)          = ''              | ''                 | 'CC71008MD01'                |'G_EC197_394_787'| '100UF'  | '100V'        | '20%'       | 'DISCRETE' | 'CAP ELEC DIP 100U 100V(20%.105C.10*20)'               | 'DIP'          | ''          | ''            | '20120110'
 '100UF'  | '100V'  | '20%'       | 'RDLLF_SEL' | 'EMPTY'    | 'SP_CC71008MD01'(!)          = ''              | ''                 | 'CC71008MD01'                |'G_EC197_394_787'| '100UF'  | '100V'        | '20%'       | 'IO'       | 'CAP ELEC DIP 100U 100V(20%.105C.10*20)'               | 'DIP'          | ''          | ''            | '20120110'
 '220UF'  | '100V'  | '20%'       | 'RDLLF'     | 'ALUM'     | 'CC72208MD00'(!)             = ''              | ''                 | 'CC72208MD00'                |'EC197_493_1240'| '220UF'  | '100V'        | '20%'       | 'DISCRETE' | 'CAP ELEC 220U 100V(20%,105C,12.5*31.5)'               | 'DIP'          | ''          | ''            | '20120116'
 '220UF'  | '100V'  | '20%'       | 'RDLLF'     | 'EMPTY'    | 'CC72208MD00'(!)             = ''              | ''                 | 'CC72208MD00'                |'EC197_493_1240'| '220UF'  | '100V'        | '20%'       | 'IO'       | 'CAP ELEC 220U 100V(20%,105C,12.5*31.5)'               | 'DIP'          | ''          | ''            | '20120116'
 '220UF'  | '100V'  | '20%'       | 'RDLLF_SEL' | 'ALUM'     | 'SP_CC72208MD00'(!)          = ''              | ''                 | 'CC72208MD00'                |'G_EC197_493_1240'| '220UF'  | '100V'        | '20%'       | 'DISCRETE' | 'CAP ELEC 220U 100V(20%,105C,12.5*31.5)'               | 'DIP'          | ''          | ''            | '20120116'
 '220UF'  | '100V'  | '20%'       | 'RDLLF_SEL' | 'EMPTY'    | 'SP_CC72208MD00'(!)          = ''              | ''                 | 'CC72208MD00'                |'G_EC197_493_1240'| '220UF'  | '100V'        | '20%'       | 'IO'       | 'CAP ELEC 220U 100V(20%,105C,12.5*31.5)'               | 'DIP'          | ''          | ''            | '20120116'
 '47UF'   | '100V'  | '20%'       | 'RDLLF_SEL' | 'ALUM'     | 'SP_TMP_S2L_JIACHENG_0213_1'(!) = ''              | ''                 | 'SP_TMP_S2L_JIACHENG_0213_1' |'G_EC197_394_492'| '47UF'   | '100V'        | '20%'       | 'DISCRETE' | 'CAP ELEC DIP 47U 100V(20%,10*12.5)SELASS'             | 'DIP'          | ''          | ''            | '20120213'
 '47UF'   | '100V'  | '20%'       | 'RDLLF_SEL' | 'EMPTY'    | 'SP_TMP_S2L_JIACHENG_0213_1'(!) = ''              | ''                 | 'SP_TMP_S2L_JIACHENG_0213_1' |'G_EC197_394_492'| '47UF'   | '100V'        | '20%'       | 'IO'       | 'CAP ELEC DIP 47U 100V(20%,10*12.5)SELASS'             | 'DIP'          | ''          | ''            | '20120213'
 '47UF'   | '100V'  | '20%'       | 'RDLLF'     | 'ALUM'     | 'CC64708MD01'(!)             = ''              | ''                 | 'CC64708MD01'                |'EC197_394_492'| '47UF'   | '100V'        | '20%'       | 'DISCRETE' | 'CAP ELEC DIP 47U 100V(20%,105C,10*12.5)'              | 'DIP'          | ''          | ''            | '20120221'
 '47UF'   | '100V'  | '20%'       | 'RDLLF'     | 'EMPTY'    | 'CC64708MD01'(!)             = ''              | ''                 | 'CC64708MD01'                |'EC197_394_492'| '47UF'   | '100V'        | '20%'       | 'IO'       | 'CAP ELEC DIP 47U 100V(20%,105C,10*12.5)'              | 'DIP'          | ''          | ''            | '20120221'
 '47UF'   | '100V'  | '20%'       | 'RDLLF_SEL' | 'ALUM'     | 'SP_CC64708MD01'(!)          = ''              | ''                 | 'CC64708MD01'                |'G_EC197_394_492'| '47UF'   | '100V'        | '20%'       | 'DISCRETE' | 'CAP ELEC DIP 47U 100V(20%,105C,10*12.5)'              | 'DIP'          | ''          | ''            | '20120221'
 '47UF'   | '100V'  | '20%'       | 'RDLLF_SEL' | 'EMPTY'    | 'SP_CC64708MD01'(!)          = ''              | ''                 | 'CC64708MD01'                |'G_EC197_394_492'| '47UF'   | '100V'        | '20%'       | 'IO'       | 'CAP ELEC DIP 47U 100V(20%,105C,10*12.5)'              | 'DIP'          | ''          | ''            | '20120221'
 '100U'   | '100V'  | '20%'       | 'RDLLF'     | 'ALUM'     | 'CC71008MD02'(!)             = ''              | ''                 | 'CC71008MD02'                |'EC197_394_787'| '100U'   | '100V'        | '20%'       | 'DISCRETE' | 'CAP ELEC DIP 100U 100V(20%,105C,10*20)'               | 'DIP'          | ''          | ''            | '20120221'
 '100U'   | '100V'  | '20%'       | 'RDLLF'     | 'EMPTY'    | 'CC71008MD02'(!)             = ''              | ''                 | 'CC71008MD02'                |'EC197_394_787'| '100U'   | '100V'        | '20%'       | 'IO'       | 'CAP ELEC DIP 100U 100V(20%,105C,10*20)'               | 'DIP'          | ''          | ''            | '20120221'
 '100U'   | '100V'  | '20%'       | 'RDLLF_SEL' | 'ALUM'     | 'SP_CC71008MD02'(!)          = ''              | ''                 | 'CC71008MD02'                |'G_EC197_394_787'| '100U'   | '100V'        | '20%'       | 'DISCRETE' | 'CAP ELEC DIP 100U 100V(20%,105C,10*20)'               | 'DIP'          | ''          | ''            | '20120221'
 '100U'   | '100V'  | '20%'       | 'RDLLF_SEL' | 'EMPTY'    | 'SP_CC71008MD02'(!)          = ''              | ''                 | 'CC71008MD02'                |'G_EC197_394_787'| '100U'   | '100V'        | '20%'       | 'IO'       | 'CAP ELEC DIP 100U 100V(20%,105C,10*20)'               | 'DIP'          | ''          | ''            | '20120221'
 '0.33F'  | '5.5V'  | '30%'       | 'RDLLF'     | 'ALUM'     | 'CCA3300TD00'(!)             = ''              | 'End of Life'      | 'CCA3300TD00'                |'EC453_P197_V_EOL'| '0.33F'  | '5.5V'        | '30%'       | 'DISCRETE' | 'CAP ELEC DIP 0.33F 5.5V(+-30%.10.5*11.5)'             | 'DIP'          | ''          | ''            | '20120308'
 '0.33F'  | '5.5V'  | '30%'       | 'RDLLF'     | 'EMPTY'    | 'CCA3300TD00'(!)             = ''              | 'End of Life'      | 'CCA3300TD00'                |'EC453_P197_V_EOL'| '0.33F'  | '5.5V'        | '30%'       | 'IO'       | 'CAP ELEC DIP 0.33F 5.5V(+-30%.10.5*11.5)'             | 'DIP'          | ''          | ''            | '20120308'
 '220UF'  | '6.3V'  | '20%'       | 'SMLF'      | 'OSCON'    | 'CC72201MZ12'(!)             = ''              | ''                 | 'CC72201MZ12'                |'EC56_197_229S'| '220UF'  | '6.3V'        | '20%'       | 'DISCRETE' | 'CAP OSCON 220U 6.3V(20%,105C,5*5.8)SMD'               | 'SMD'          | ''          | ''            | '20120308'
 '220UF'  | '6.3V'  | '20%'       | 'SMLF'      | 'EMPTY'    | 'CC72201MZ12'(!)             = ''              | ''                 | 'CC72201MZ12'                |'EC56_197_229S'| '220UF'  | '6.3V'        | '20%'       | 'IO'       | 'CAP OSCON 220U 6.3V(20%,105C,5*5.8)SMD'               | 'SMD'          | ''          | ''            | '20120308'
 '390UF'  | '2.5V'  | '20%'       | 'SMLF'      | 'OSCON'    | 'CC7390JMZ01'(!)             = ''              | ''                 | 'CC7390JMZ01'                |'EC56_197_229S'| '390UF'  | '2.5V'        | '20%'       | 'DISCRETE' | 'CAP OSCON 390U 2.5V(20%,105C,5*5.8)SMD'               | 'SMD'          | ''          | ''            | '20120308'
 '390UF'  | '2.5V'  | '20%'       | 'SMLF'      | 'EMPTY'    | 'CC7390JMZ01'(!)             = ''              | ''                 | 'CC7390JMZ01'                |'EC56_197_229S'| '390UF'  | '2.5V'        | '20%'       | 'IO'       | 'CAP OSCON 390U 2.5V(20%,105C,5*5.8)SMD'               | 'SMD'          | ''          | ''            | '20120308'
 '470UF'  | '2V'    | '20%'       | 'RDLLF'     | 'C_POSCAP' | 'CH747RM8800'(!)             = ''              | ''                 | 'CH747RM8800'                |'TAJ_D2'| '470UF'  | '2V'          | '20%'       | 'DISCRETE' | 'CAP CHIP 470U 2V(+-20%,ESR6,7343,H1.9)'               | 'SMT'          | ''          | ''            | '20120326'
 '470UF'  | '2V'    | '20%'       | 'RDLLF'     | 'EMPTY'    | 'CH747RM8800'(!)             = ''              | ''                 | 'CH747RM8800'                |'TAJ_D2'| '470UF'  | '2V'          | '20%'       | 'IO'       | 'CAP CHIP 470U 2V(+-20%,ESR6,7343,H1.9)'               | 'SMT'          | ''          | ''            | '20120326'
 '330UF'  | '2V'    | '35%'       | 'RDLLF'     | 'C_POSCAP' | 'CH733RY8802'(!)             = ''              | ''                 | 'CH733RY8802'                | 'TAJ_SX'                   | '330UF'  | '2V'          | '35%'       | 'DISCRETE' | 'CAP CHIP 330U 2V(+10/-35%,7343,LES=9)'                | 'SMT'          | ''          | ''            | '20120326'
 '330UF'  | '2V'    | '35%'       | 'RDLLF'     | 'EMPTY'    | 'CH733RY8802'(!)             = ''              | ''                 | 'CH733RY8802'                | 'TAJ_SX'                   | '330UF'  | '2V'          | '35%'       | 'IO'       | 'CAP CHIP 330U 2V(+10/-35%,7343,LES=9)'                | 'SMT'          | ''          | ''            | '20120326'
 '470UF'  | '2V'    | '35%'       | 'RDLLF'     | 'C_POSCAP' | 'CH747RY8800'(!)             = ''              | ''                 | 'CH747RY8800'                | 'TAJ_D'                    | '470UF'  | '2V'          | '35%'       | 'DISCRETE' | 'CAP CHIP 470U 2V(+10/-35%.ESR=9.7343)'                | 'SMT'          | ''          | ''            | '20120326'
 '470UF'  | '2V'    | '35%'       | 'RDLLF'     | 'EMPTY'    | 'CH747RY8800'(!)             = ''              | ''                 | 'CH747RY8800'                | 'TAJ_D'                    | '470UF'  | '2V'          | '35%'       | 'IO'       | 'CAP CHIP 470U 2V(+10/-35%.ESR=9.7343)'                | 'SMT'          | ''          | ''            | '20120326'
 '470UF'  | '2V'    | '20%'       | 'RDLLF'     | 'C_POSCAP' | 'CH747RM8802'(!)             = ''              | ''                 | 'CH747RM8802'                |'TAJ_SX'| '470UF'  | '2V'          | '20%'       | 'DISCRETE' | 'CAP CHIP 470U 2V(+-20%,ESR9,7343,H1.9)'               | 'SMT'          | ''          | ''            | '20120326'
 '470UF'  | '2V'    | '20%'       | 'RDLLF'     | 'EMPTY'    | 'CH747RM8802'(!)             = ''              | ''                 | 'CH747RM8802'                |'TAJ_SX'| '470UF'  | '2V'          | '20%'       | 'IO'       | 'CAP CHIP 470U 2V(+-20%,ESR9,7343,H1.9)'               | 'SMT'          | ''          | ''            | '20120326'
 '330UF'  | '2V'    | '20%'       | 'RDLLF'     | 'C_POSCAP' | 'CH733RM8866'(!)             = ''              | ''                 | 'CH733RM8866'                | 'TAJ_SX'                   | '330UF'  | '2V'          | '20%'       | 'DISCRETE' | 'CAP CHIP 330U 2V(20%,ESR=6,7343,H1.9)'                | 'SMT'          | ''          | ''            | '20120326'
 '330UF'  | '2V'    | '20%'       | 'RDLLF'     | 'EMPTY'    | 'CH733RM8866'(!)             = ''              | ''                 | 'CH733RM8866'                | 'TAJ_SX'                   | '330UF'  | '2V'          | '20%'       | 'IO'       | 'CAP CHIP 330U 2V(20%,ESR=6,7343,H1.9)'                | 'SMT'          | ''          | ''            | '20120326'
 '100UF'  | '16V'   | '20%'       | 'RDLLF'     | 'OSCON'    | 'CC71003MZ23'(!)             = ''              | ''                 | 'CC71003MZ23'                |'EC56_197_229S'| '100UF'  | '16V'         | '20%'       | 'DISCRETE' | 'CAP OSCON SMD 100U 16V(20%,105C,5*5.8)'               | 'SMT'          | ''          | ''            | '20120525'
 '100UF'  | '16V'   | '20%'       | 'RDLLF'     | 'EMPTY'    | 'CC71003MZ23'(!)             = ''              | ''                 | 'CC71003MZ23'                |'EC56_197_229S'| '100UF'  | '16V'         | '20%'       | 'IO'       | 'CAP OSCON SMD 100U 16V(20%,105C,5*5.8)'               | 'SMT'          | ''          | ''            | '20120525'
 '220U'   | '6.3V'  | '35%'       | 'RDLLF'     | 'C_POSCAP' | 'CH7221Y8800'(!)             = ''              | ''                 | 'CH7221Y8800'                |'TAJ_DXC'| '220U'   | '6.3V'        | '35%'       | 'DISCRETE' | 'CAP 220U 6.3V(+10/-35%,ESR15,7343)H1.9'               | 'SMT'          | ''          | ''            | '20120601'
 '220U'   | '6.3V'  | '35%'       | 'RDLLF'     | 'EMPTY'    | 'CH7221Y8800'(!)             = ''              | ''                 | 'CH7221Y8800'                |'TAJ_DXC'| '220U'   | '6.3V'        | '35%'       | 'IO'       | 'CAP 220U 6.3V(+10/-35%,ESR15,7343)H1.9'               | 'SMT'          | ''          | ''            | '20120601'
 '180UF'  | '16V'   | '20%'       | 'RDLLF'     | 'ALUM'     | 'CC71803MZ03'(!)             = ''              | ''                 | 'CC71803MZ03'                |'EC83_248_232S'| '180UF'  | '16V'         | '20%'       | 'DISCRETE' | 'CAP OSCON SMD 180U 16V(20%.105C.6.3*5.9))'            | 'SMT'          | ''          | ''            | '20120726'
 '180UF'  | '16V'   | '20%'       | 'RDLLF'     | 'EMPTY'    | 'CC71803MZ03'(!)             = ''              | ''                 | 'CC71803MZ03'                |'EC83_248_232S'| '180UF'  | '16V'         | '20%'       | 'IO'       | 'CAP OSCON SMD 180U 16V(20%.105C.6.3*5.9))'            | 'SMT'          | ''          | ''            | '20120726'
 '330UF'  | '2.5V'  | '20%'       | 'RDLLF'     | 'SP-CAP'   | 'CH733LM8800'(!)             = 'End of Design' | 'Comp-Approve'     | 'CH733LM8800'                |'TAJ_SX'| '330UF'  | '2.5V'        | '20%'       | 'DISCRETE' | 'CAP CHIP 330U 2.5V(+-20%,ESR6,7343)H1.9'              | 'SMT'          | ''          | ''            | '20120815'
 '330UF'  | '2.5V'  | '20%'       | 'RDLLF'     | 'EMPTY'    | 'CH733LM8800'(!)             = 'End of Design' | 'Comp-Approve'     | 'CH733LM8800'                |'TAJ_SX'| '330UF'  | '2.5V'        | '20%'       | 'IO'       | 'CAP CHIP 330U 2.5V(+-20%,ESR6,7343)H1.9'              | 'SMT'          | ''          | ''            | '20120815'
 '470UF'  | '10V'   | '20%'       | 'RDLLF'     | 'ALUM'     | 'CC74702MD03'(!)             = ''              | ''                 | 'CC74702MD03'                |'EC98_248_433'| '470UF'  | '10V'         | '20%'       | 'DISCRETE' | 'CAP ELEC DIP 470U 10V(+-20%,105C,6.3*11)'             | 'DIP'          | ''          | ''            | '20120924'
 '470UF'  | '10V'   | '20%'       | 'RDLLF'     | 'EMPTY'    | 'CC74702MD03'(!)             = ''              | ''                 | 'CC74702MD03'                |'EC98_248_433'| '470UF'  | '10V'         | '20%'       | 'IO'       | 'CAP ELEC DIP 470U 10V(+-20%,105C,6.3*11)'             | 'DIP'          | ''          | ''            | '20120924'
 '100UF'  | '16V'   | '20%'       | 'RDLLF'     | 'ALUM'     | 'CC71003MZ14'(!)             = 'End of Design' | 'Comp-Approve'     | 'CC71003MZ14'                |'EC71_248_229S'| '100UF'  | '16V'         | '20%'       | 'DISCRETE' | 'CAP SMD 100U 16V(+-20%,105C,6.3*5.8)'                 | 'SMT'          | ''          | ''            | '20121214'
 '100UF'  | '16V'   | '20%'       | 'RDLLF'     | 'EMPTY'    | 'CC71003MZ14'(!)             = 'End of Design' | 'Comp-Approve'     | 'CC71003MZ14'                |'EC71_248_229S'| '100UF'  | '16V'         | '20%'       | 'IO'       | 'CAP SMD 100U 16V(+-20%,105C,6.3*5.8)'                 | 'SMT'          | ''          | ''            | '20121214'
 '1F'     | '5.5V'  | '80%'       | 'RDLLF'     | 'ALUM'     | 'CCB1000ZD00'(!)             = ''              | ''                 | 'CCB1000ZD00'                |'EC297_847_512'| '1F'     | '5.5V'        | '80%'       | 'DISCRETE' | 'CAP ELEC DIP 1F 5.5V (+80%-20%,21.5*13)'              | 'DIP'          | ''          | ''            | '20130110'
 '1F'     | '5.5V'  | '80%'       | 'RDLLF'     | 'EMPTY'    | 'CCB1000ZD00'(!)             = ''              | ''                 | 'CCB1000ZD00'                |'EC297_847_512'| '1F'     | '5.5V'        | '80%'       | 'IO'       | 'CAP ELEC DIP 1F 5.5V (+80%-20%,21.5*13)'              | 'DIP'          | ''          | ''            | '20130110'
 '470UF'  | '2.5V'  | '20%'       | 'RDLF'      | 'POSCAP'   | 'CH747LM8814'(!)             = ''              | ''                 | 'CH747LM8814'                |'TAJ_SX'| '470UF'  | '2.5V'        | '20%'       | 'DISCRETE' | 'CAP CHIP 470U 2.5V(20%,ESR4.5,7343,H1.9)'             | 'SMT'          | ''          | ''            | '20130325'
 '470UF'  | '2.5V'  | '20%'       | 'RDLF'      | 'EMPTY'    | 'CH747LM8814'(!)             = ''              | ''                 | 'CH747LM8814'                |'TAJ_SX'| '470UF'  | '2.5V'        | '20%'       | 'IO'       | 'CAP CHIP 470U 2.5V(20%,ESR4.5,7343,H1.9)'             | 'SMT'          | ''          | ''            | '20130325'
 '560UF'  | '2.5V'  | '20%'       | 'RDLF'      | 'ALUM'     | 'CC7560JMD09'(!)             = ''              | ''                 | 'CC7560JMD09'                |'EC98_248_237'| '560UF'  | '2.5V'        | '20%'       | 'DISCRETE' | 'CAP OSCON DIP 560U 2.5V(20%,105C,6.3*6)'              | 'DIP'          | ''          | ''            | '20130403'
 '560UF'  | '2.5V'  | '20%'       | 'RDLF'      | 'EMPTY'    | 'CC7560JMD09'(!)             = ''              | ''                 | 'CC7560JMD09'                |'EC98_248_237'| '560UF'  | '2.5V'        | '20%'       | 'IO'       | 'CAP OSCON DIP 560U 2.5V(20%,105C,6.3*6)'              | 'DIP'          | ''          | ''            | '20130403'
 '220UF'  | '2.5V'  | '20%'       | 'SMLF'      | 'TANT'     | 'CH722LM8816'(!)             = ''              | ''                 | 'CH722LM8816'                |'TAJ_D2'| '220UF'  | '2.5V'        | '20%'       | 'DISCRETE' | 'CAP CHIP 220U2.5V(20%,ESR15,7343,H1.9)'               | 'SMT'          | ''          | ''            | '20130417'
 '220UF'  | '2.5V'  | '20%'       | 'SMLF'      | 'EMPTY'    | 'CH722LM8816'(!)             = ''              | ''                 | 'CH722LM8816'                |'TAJ_D2'| '220UF'  | '2.5V'        | '20%'       | 'IO'       | 'CAP CHIP 220U2.5V(20%,ESR15,7343,H1.9)'               | 'SMT'          | ''          | ''            | '20130417'
 '820UF'  | '16V'   | '20%'       | 'RDLF'      | 'ALUM'     | 'CC78203MD00'(!)             = ''              | ''                 | 'CC78203MD00'                |'EC197_394_453'| '820UF'  | '16V'         | '20%'       | 'DISCRETE' | 'CAP OSCON DIP 820U 16V(20%,105C,10*11.5)'             | 'DIP'          | ''          | ''            | '20130507'
 '820UF'  | '16V'   | '20%'       | 'RDLF'      | 'EMPTY'    | 'CC78203MD00'(!)             = ''              | ''                 | 'CC78203MD00'                |'EC197_394_453'| '820UF'  | '16V'         | '20%'       | 'IO'       | 'CAP OSCON DIP 820U 16V(20%,105C,10*11.5)'             | 'DIP'          | ''          | ''            | '20130507'
 '100UF'  | '100V'  | '20%'       | 'RDLF'      | 'ALUM'     | 'CC71008MD04'(!)             = 'End of Design' | 'P/N Release'      | 'CC71008MD04'                |'EC197_493_630'| '100UF'  | '100V'        | '20%'       | 'DISCRETE' | 'CAP ELEC DIP 100U 100V(20%,105C,12.5*16)'             | 'DIP'          | ''          | ''            | '20130521'
 '100UF'  | '100V'  | '20%'       | 'RDLF'      | 'EMPTY'    | 'CC71008MD04'(!)             = 'End of Design' | 'P/N Release'      | 'CC71008MD04'                |'EC197_493_630'| '100UF'  | '100V'        | '20%'       | 'IO'       | 'CAP ELEC DIP 100U 100V(20%,105C,12.5*16)'             | 'DIP'          | ''          | ''            | '20130521'
 '470UF'  | '16V'   | '20%'       | 'RDLF'      | 'OSCON'    | 'CC74703MD24'(!)             = ''              | ''                 | 'CC74703MD24'                |'EC3-5_8-5_9'| '470UF'  | '16V'         | '20%'       | 'DISCRETE' | 'CAP OSCON DIP 470U 16V(+-20%,ESR16,8*8)'              | 'DIP'          | ''          | ''            | '20130528'
 '470UF'  | '16V'   | '20%'       | 'RDLF'      | 'EMPTY'    | 'CC74703MD24'(!)             = ''              | ''                 | 'CC74703MD24'                |'EC3-5_8-5_9'| '470UF'  | '16V'         | '20%'       | 'IO'       | 'CAP OSCON DIP 470U 16V(+-20%,ESR16,8*8)'              | 'DIP'          | ''          | ''            | '20130528'
 '100UF'  | '10V'   | '20%'       | 'SMLF'      | 'TANT'     | 'CH7102MT800'(!)             = ''              | ''                 | 'CH7102MT800'                |'TAJ_D3L'| '100UF'  | '10V'         | '20%'       | 'DISCRETE' | 'CAPCHIP 100U 10V(20%,ESR55,TAN,7343)H2.8'             | 'SMT'          | ''          | ''            | '20130802'
 '100UF'  | '10V'   | '20%'       | 'SMLF'      | 'EMPTY'    | 'CH7102MT800'(!)             = ''              | ''                 | 'CH7102MT800'                |'TAJ_D3L'| '100UF'  | '10V'         | '20%'       | 'IO'       | 'CAPCHIP 100U 10V(20%,ESR55,TAN,7343)H2.8'             | 'SMT'          | ''          | ''            | '20130802'
 '33UF'   | '16V'   | '20%'       | 'SMLF'      | 'TANT'     | 'CH6333M8807'(!)             = 'End of Design' | 'Comp-Approve'     | 'CH6333M8807'                |'TAJ_D2'| '33UF'   | '16V'         | '20%'       | 'DISCRETE' | 'CAP CHIP 33U 16V(+-20%,ESR60,7343)H1.9EP'             | 'SMT'          | ''          | ''            | '20130904'
 '33UF'   | '16V'   | '20%'       | 'SMLF'      | 'EMPTY'    | 'CH6333M8807'(!)             = 'End of Design' | 'Comp-Approve'     | 'CH6333M8807'                |'TAJ_D2'| '33UF'   | '16V'         | '20%'       | 'IO'       | 'CAP CHIP 33U 16V(+-20%,ESR60,7343)H1.9EP'             | 'SMT'          | ''          | ''            | '20130904'
 '560UF'  | '2.5V'  | '20%'       | 'RDLF'      | 'OSCON'    | 'SP_CC7560JMD07'(!)          = 'End of Design' | 'Comp-Release Qty' | 'CC7560JMD07'                |'EC98_248_237_T6MG'| '560UF'  | '2.5V'        | '20%'       | 'DISCRETE' | 'CAP OS-C 560U 2.5V(20%,ESR13,6.3*5)'                  | 'DIP'          | ''          | ''            | '20131018'
 '560UF'  | '2.5V'  | '20%'       | 'RDLF'      | 'EMPTY'    | 'SP_CC7560JMD07'(!)          = 'End of Design' | 'Comp-Release Qty' | 'CC7560JMD07'                |'EC98_248_237_T6MG'| '560UF'  | '2.5V'        | '20%'       | 'IO'       | 'CAP OS-C 560U 2.5V(20%,ESR13,6.3*5)'                  | 'DIP'          | ''          | ''            | '20131018'
 '270UF'  | '16V'   | '20%'       | 'RDLF'      | 'OSCON'    | 'SP_CC72703MD03-1'(!)        = ''              | ''                 | 'CC72703MD03'                |'EC138_315_354A_T6MG'| '270UF'  | '16V'         | '20%'       | 'DISCRETE' | 'CAP OSCON DIP 270U 16V(+-20%,8*9)'                    | 'DIP'          | ''          | ''            | '20131018'
 '270UF'  | '16V'   | '20%'       | 'RDLF'      | 'EMPTY'    | 'SP_CC72703MD03-1'(!)        = ''              | ''                 | 'CC72703MD03'                |'EC138_315_354A_T6MG'| '270UF'  | '16V'         | '20%'       | 'IO'       | 'CAP OSCON DIP 270U 16V(+-20%,8*9)'                    | 'DIP'          | ''          | ''            | '20131018'
 '820UF'  | '2.5V'  | '20%'       | 'RDLF'      | 'OSCON'    | 'SP_CC7820JMD01-1'(!)        = ''              | ''                 | 'CC7820JMD01'                |'EC98_248_315_T6MG'| '820UF'  | '2.5V'        | '20%'       | 'DISCRETE' | 'CAP OSCON DIP 820U 2.5V(+-20%,6.3*8)'                 | 'DIP'          | ''          | ''            | '20131018'
 '820UF'  | '2.5V'  | '20%'       | 'RDLF'      | 'EMPTY'    | 'SP_CC7820JMD01-1'(!)        = ''              | ''                 | 'CC7820JMD01'                |'EC98_248_315_T6MG'| '820UF'  | '2.5V'        | '20%'       | 'IO'       | 'CAP OSCON DIP 820U 2.5V(+-20%,6.3*8)'                 | 'DIP'          | ''          | ''            | '20131018'
 '270UF'  | '16V'   | '20%'       | 'RDLF'      | 'OSCON'    | 'SP_CC72703MD19-1'(!)        = ''              | ''                 | 'CC72703MD19'                |'EC98_248_315_T6MG'| '270UF'  | '16V'         | '20%'       | 'DISCRETE' | 'CAP OSCON DIP 270U 16V(20%,105C,6.3*8)'               | 'DIP'          | ''          | ''            | '20131018'
 '270UF'  | '16V'   | '20%'       | 'RDLF'      | 'EMPTY'    | 'SP_CC72703MD19-1'(!)        = ''              | ''                 | 'CC72703MD19'                |'EC98_248_315_T6MG'| '270UF'  | '16V'         | '20%'       | 'IO'       | 'CAP OSCON DIP 270U 16V(20%,105C,6.3*8)'               | 'DIP'          | ''          | ''            | '20131018'
 '560UF'  | '6.3V'  | '20%'       | 'RDLF'      | 'OSCON'    | 'SP_CC75601MD01-1'(!)        = ''              | ''                 | 'CC75601MD01'                |'EC98_248_315_T6MG'| '560UF'  | '6.3V'        | '20%'       | 'DISCRETE' | 'CAP OSCON DIP 560U 6.3V(+-20%,6.3*8)'                 | 'DIP'          | ''          | ''            | '20131018'
 '560UF'  | '6.3V'  | '20%'       | 'RDLF'      | 'EMPTY'    | 'SP_CC75601MD01-1'(!)        = ''              | ''                 | 'CC75601MD01'                |'EC98_248_315_T6MG'| '560UF'  | '6.3V'        | '20%'       | 'IO'       | 'CAP OSCON DIP 560U 6.3V(+-20%,6.3*8)'                 | 'DIP'          | ''          | ''            | '20131018'
 '560UF'  | '2.5V'  | '20%'       | 'RDLF'      | 'OSCON'    | 'CC7560JMD07'(!)             = 'End of Design' | 'Comp-Release Qty' | 'CC7560JMD07'                |'EC98_248_237'| '560UF'  | '2.5V'        | '20%'       | 'DISCRETE' | 'CAP OS-C 560U 2.5V(20%,ESR13,6.3*5)'                  | 'DIP'          | ''          | ''            | '20131018'
 '560UF'  | '2.5V'  | '20%'       | 'RDLF'      | 'EMPTY'    | 'CC7560JMD07'(!)             = 'End of Design' | 'Comp-Release Qty' | 'CC7560JMD07'                |'EC98_248_237'| '560UF'  | '2.5V'        | '20%'       | 'IO'       | 'CAP OS-C 560U 2.5V(20%,ESR13,6.3*5)'                  | 'DIP'          | ''          | ''            | '20131018'
 '270UF'  | '16V'   | '20%'       | 'RDLF'      | 'OSCON'    | 'CC72703MD19'(!)             = ''              | ''                 | 'CC72703MD19'                |'EC2-5_6-8_9'| '270UF'  | '16V'         | '20%'       | 'DISCRETE' | 'CAP OSCON DIP 270U 16V(20%,105C,6.3*8)'               | 'DIP'          | ''          | ''            | '20131018'
 '270UF'  | '16V'   | '20%'       | 'RDLF'      | 'EMPTY'    | 'CC72703MD19'(!)             = ''              | ''                 | 'CC72703MD19'                |'EC2-5_6-8_9'| '270UF'  | '16V'         | '20%'       | 'IO'       | 'CAP OSCON DIP 270U 16V(20%,105C,6.3*8)'               | 'DIP'          | ''          | ''            | '20131018'
 '330UF'  | '6.3V'  | '20%'       | 'SMLF'      | 'POSCAP'   | 'CH7331M8851'(!)             = 'End of Design' | 'Comp-Approve'     | 'CH7331M8851'                |'TAJ_D3L'| '330UF'  | '6.3V'        | '20%'       | 'DISCRETE' | 'CAP CHIP330U 6.3V(20%,ESR18,7343,H2.8)'               | 'SMT'          | ''          | ''            | '20131024'
 '330UF'  | '6.3V'  | '20%'       | 'SMLF'      | 'EMPTY'    | 'CH7331M8851'(!)             = 'End of Design' | 'Comp-Approve'     | 'CH7331M8851'                |'TAJ_D3L'| '330UF'  | '6.3V'        | '20%'       | 'IO'       | 'CAP CHIP330U 6.3V(20%,ESR18,7343,H2.8)'               | 'SMT'          | ''          | ''            | '20131024'
 '470UF'  | '16V'   | '20%'       | 'SMLF'      | 'ALUM'     | 'CC74703MZ00'(!)             = ''              | ''                 | 'CC74703MZ00'                |'EC123_315_394S'| '470UF'  | '16V'         | '20%'       | 'DISCRETE' | 'CAP ELEC SMD 470U 16V(+-20%,105C,8*10)'               | 'SMT'          | ''          | ''            | '20131105'
 '470UF'  | '16V'   | '20%'       | 'SMLF'      | 'EMPTY'    | 'CC74703MZ00'(!)             = ''              | ''                 | 'CC74703MZ00'                |'EC123_315_394S'| '470UF'  | '16V'         | '20%'       | 'IO'       | 'CAP ELEC SMD 470U 16V(+-20%,105C,8*10)'               | 'SMT'          | ''          | ''            | '20131105'
 '47UF'   | '100V'  | '20%'       | 'RDLF'      | 'ALUM'     | 'SP_CC64708MD01_1'(!)        = ''              | ''                 | 'CC64708MD01'                |'G_EC197_394_492_T2L'| '47UF'   | '100V'        | '20%'       | 'DISCRETE' | 'CAP ELEC DIP 47U 100V(20%,105C,10*12.5)'              | 'DIP'          | ''          | ''            | '20131114'
 '47UF'   | '100V'  | '20%'       | 'RDLF'      | 'EMPTY'    | 'SP_CC64708MD01_1'(!)        = ''              | ''                 | 'CC64708MD01'                |'G_EC197_394_492_T2L'| '47UF'   | '100V'        | '20%'       | 'IO'       | 'CAP ELEC DIP 47U 100V(20%,105C,10*12.5)'              | 'DIP'          | ''          | ''            | '20131114'
 '330UF'  | '6.3V'  | '20%'       | 'SMLF'      | 'POSCAP'   | 'CH7331M8826'(!)             = ''              | 'Comp-Approve'     | 'CH7331M8826'                | 'TAJ_D2E'                  | '330UF'  | '6.3V'        | '20%'       | 'DISCRETE' | 'CAP 330U 6.3V(+-20%,ESR25M,7343,H=1.9)'               | 'SMT'          | ''          | ''            | '20131216'
 '330UF'  | '6.3V'  | '20%'       | 'SMLF'      | 'EMPTY'    | 'CH7331M8826'(!)             = ''              | 'Comp-Approve'     | 'CH7331M8826'                | 'TAJ_D2E'                  | '330UF'  | '6.3V'        | '20%'       | 'IO'       | 'CAP 330U 6.3V(+-20%,ESR25M,7343,H=1.9)'               | 'SMT'          | ''          | ''            | '20131216'
 '330UF'  | '2.5V'  | '20%'       | 'SMLF'      | 'POSCAP'   | 'CH733LM8604'(!)             = ''              | ''                 | 'CH733LM8604'                |'TAJ_B2XA'| '330UF'  | '2.5V'        | '20%'       | 'DISCRETE' | 'CAP CHIP 330U 2.5V(+-20%,ESR9,3528)H1.9'              | 'SMT'          | ''          | ''            | '20131218'
 '330UF'  | '2.5V'  | '20%'       | 'SMLF'      | 'EMPTY'    | 'CH733LM8604'(!)             = ''              | ''                 | 'CH733LM8604'                |'TAJ_B2XA'| '330UF'  | '2.5V'        | '20%'       | 'IO'       | 'CAP CHIP 330U 2.5V(+-20%,ESR9,3528)H1.9'              | 'SMT'          | ''          | ''            | '20131218'
 '560UF'  | '2V'    | '20%'       | 'SMLF'      | 'POSCAP'   | 'CH756RM8802'(!)             = ''              | ''                 | 'CH756RM8802'                |'TAJ_SX'| '560UF'  | '2V'          | '20%'       | 'DISCRETE' | 'CAP CHIP 560U 2V(20%,ESR4.5,7343,H1.9)'               | 'SMT'          | ''          | ''            | '20140116'
 '560UF'  | '2V'    | '20%'       | 'SMLF'      | 'EMPTY'    | 'CH756RM8802'(!)             = ''              | ''                 | 'CH756RM8802'                |'TAJ_SX'| '560UF'  | '2V'          | '20%'       | 'IO'       | 'CAP CHIP 560U 2V(20%,ESR4.5,7343,H1.9)'               | 'SMT'          | ''          | ''            | '20140116'
 '470UF'  | '2.5V'  | '20%'       | 'SMLF'      | 'POSCAP'   | 'CH747LM8816'(!)             = ''              | ''                 | 'CH747LM8816'                |'TAJ_DXC'| '470UF'  | '2.5V'        | '20%'       | 'DISCRETE' | 'CAP CHIP 470U 2.5V(20%,ESR3M,7343,SPCAP)'             | 'SMT'          | ''          | ''            | '20140121'
 '470UF'  | '2.5V'  | '20%'       | 'SMLF'      | 'EMPTY'    | 'CH747LM8816'(!)             = ''              | ''                 | 'CH747LM8816'                |'TAJ_DXC'| '470UF'  | '2.5V'        | '20%'       | 'IO'       | 'CAP CHIP 470U 2.5V(20%,ESR3M,7343,SPCAP)'             | 'SMT'          | ''          | ''            | '20140121'
 '470UF'  | '16V'   | '20%'       | 'SMLF'      | 'OSCON'    | 'CC74703MZ05'(!)             = ''              | ''                 | 'CC74703MZ05'                |'EC181_394_496SXA'| '470UF'  | '16V'         | '20%'       | 'DISCRETE' | 'CAP OSCON SMD 470UF 16V(105C,20%,10*12.6'             | 'SMT'          | ''          | ''            | '20221116'
 '470UF'  | '16V'   | '20%'       | 'SMLF'      | 'EMPTY'    | 'CC74703MZ05'(!)             = ''              | ''                 | 'CC74703MZ05'                |'EC181_394_496SXA'| '470UF'  | '16V'         | '20%'       | 'IO'       | 'CAP OSCON SMD 470UF 16V(105C,20%,10*12.6'             | 'SMT'          | ''          | ''            | '20221116'
 '100UF'  | '16V'   | '20%'       | 'SMLF'      | 'ALUM'     | 'CH7103M8803'(!)             = 'End of Design' | 'Comp-Approve'     | 'CH7103M8803'                |'TAJ_D9'| '100UF'  | '16V'         | '20%'       | 'DISCRETE' | 'CAP CHIP 100UF 16V(20%,ESR12,SPCAP,7343)'             | 'SMT'          | ''          | ''            | '20140326'
 '100UF'  | '16V'   | '20%'       | 'SMLF'      | 'EMPTY'    | 'CH7103M8803'(!)             = 'End of Design' | 'Comp-Approve'     | 'CH7103M8803'                |'TAJ_D9'| '100UF'  | '16V'         | '20%'       | 'IO'       | 'CAP CHIP 100UF 16V(20%,ESR12,SPCAP,7343)'             | 'SMT'          | ''          | ''            | '20140326'
 '470UF'  | '6.3V'  | '20%'       | 'SMLF'      | 'ALUM'     | 'CH7471MI800'(!)             = ''              | ''                 | 'CH7471MI800'                |'TAJ_D4XA_H158'| '470UF'  | '6.3V'        | '20%'       | 'DISCRETE' | 'CAP CHIP 470U 6.3V(20%,POSCAP(TAN),7343)'             | 'SMT'          | ''          | ''            | '20140326'
 '470UF'  | '6.3V'  | '20%'       | 'SMLF'      | 'EMPTY'    | 'CH7471MI800'(!)             = ''              | ''                 | 'CH7471MI800'                |'TAJ_D4XA_H158'| '470UF'  | '6.3V'        | '20%'       | 'IO'       | 'CAP CHIP 470U 6.3V(20%,POSCAP(TAN),7343)'             | 'SMT'          | ''          | ''            | '20140326'
 '100UF'  | '16V'   | '20%'       | 'SMLF'      | 'OSCON'    | 'CC71003MZ11'(!)             = ''              | ''                 | 'CC71003MZ11'                |'EC83_248_225S'| '100UF'  | '16V'         | '20%'       | 'DISCRETE' | 'CAP OSCON SMD 100U 16V(20%.105C.6.3*5.7)'             | 'SMT'          | ''          | ''            | '20140327'
 '100UF'  | '16V'   | '20%'       | 'SMLF'      | 'EMPTY'    | 'CC71003MZ11'(!)             = ''              | ''                 | 'CC71003MZ11'                |'EC83_248_225S'| '100UF'  | '16V'         | '20%'       | 'IO'       | 'CAP OSCON SMD 100U 16V(20%.105C.6.3*5.7)'             | 'SMT'          | ''          | ''            | '20140327'
 '47UF'   | '100V'  | '20%'       | 'RDLF'      | 'ALUM'     | 'CC64708MD02'(!)             = 'End of Design' | 'Comp-Approve'     | 'CC64708MD02'                |'EC3-5_8-5_13'| '47UF'   | '100V'        | '20%'       | 'DISCRETE' | 'CAP ELEC DIP 47U 100V(20%,105C,8*11.5)'               | 'DIP'          | ''          | ''            | '20140331'
 '47UF'   | '100V'  | '20%'       | 'RDLF'      | 'EMPTY'    | 'CC64708MD02'(!)             = 'End of Design' | 'Comp-Approve'     | 'CC64708MD02'                |'EC3-5_8-5_13'| '47UF'   | '100V'        | '20%'       | 'IO'       | 'CAP ELEC DIP 47U 100V(20%,105C,8*11.5)'               | 'DIP'          | ''          | ''            | '20140331'
 '100UF'  | '100V'  | '20%'       | 'RDLF'      | 'ALUM'     | 'CC71008MD05'(!)             = ''              | ''                 | 'CC71008MD05'                |'EC197_394_630'| '100UF'  | '100V'        | '20%'       | 'DISCRETE' | 'CAP ELEC DIP 100U 100V(20%,105C,10*16)'               | 'DIP'          | ''          | ''            | '20140331'
 '100UF'  | '100V'  | '20%'       | 'RDLF'      | 'EMPTY'    | 'CC71008MD05'(!)             = ''              | ''                 | 'CC71008MD05'                |'EC197_394_630'| '100UF'  | '100V'        | '20%'       | 'IO'       | 'CAP ELEC DIP 100U 100V(20%,105C,10*16)'               | 'DIP'          | ''          | ''            | '20140331'
 '680UF'  | '2.5V'  | '20%'       | 'SMLF'      | 'ESR7'     | 'CH768LM8819'(!)             = ''              | ''                 | 'CH768LM8819'                |'TAJ_DXD'| '680UF'  | '2.5V'        | '20%'       | 'DISCRETE' | 'CAP CHIP 680U 2.5V (20%,ESR7,7343,H2.8)'              | 'SMT'          | ''          | ''            | '20140429'
 '680UF'  | '2.5V'  | '20%'       | 'SMLF'      | 'EMPTY'    | 'CH768LM8819'(!)             = ''              | ''                 | 'CH768LM8819'                |'TAJ_DXD'| '680UF'  | '2.5V'        | '20%'       | 'IO'       | 'CAP CHIP 680U 2.5V (20%,ESR7,7343,H2.8)'              | 'SMT'          | ''          | ''            | '20140429'
 '680UF'  | '16V'   | '20%'       | 'SMLF'      | 'ALUM'     | 'CC76803MZ11'(!)             = ''              | ''                 | 'CC76803MZ11'                |'EC181_394_402S'| '680UF'  | '16V'         | '20%'       | 'DISCRETE' | 'CAP ELEC SMD 680U 16V(20%,105,10X10)'                 | 'SMT'          | ''          | ''            | '20140610'
 '680UF'  | '16V'   | '20%'       | 'SMLF'      | 'EMPTY'    | 'CC76803MZ11'(!)             = ''              | ''                 | 'CC76803MZ11'                |'EC181_394_402S'| '680UF'  | '16V'         | '20%'       | 'IO'       | 'CAP ELEC SMD 680U 16V(20%,105,10X10)'                 | 'SMT'          | ''          | ''            | '20140610'
 '680UF'  | '6.3V'  | '20%'       | 'SMLF'      | 'TANT'     | 'TMP_S2B_ALVIN_0526_1'(!)    = ''              | ''                 | 'TMP_S2B_ALVIN_0526_1'       | 'TAJ_D4XA'                 | '680UF'  | '6.3V'        | '20%'       | 'DISCRETE' | 'CAP 680U 6.3V (+-20%.ESR25M.7343.H=3.8)'              | 'SMT'          | ''          | ''            | '20140527'
 '680UF'  | '6.3V'  | '20%'       | 'SMLF'      | 'EMPTY'    | 'TMP_S2B_ALVIN_0526_1'(!)    = ''              | ''                 | 'TMP_S2B_ALVIN_0526_1'       | 'TAJ_D4XA'                 | '680UF'  | '6.3V'        | '20%'       | 'IO'       | 'CAP 680U 6.3V (+-20%.ESR25M.7343.H=3.8)'              | 'SMT'          | ''          | ''            | '20140527'
 '680UF'  | '4V'    | '20%'       | 'SMLF'      | 'TANT'     | 'CH7680KMT80'(!)             = ''              | ''                 | 'CH7680KMT80'                |'TAJ_D4'| '680UF'  | '4V'          | '20%'       | 'DISCRETE' | 'CAP CHIP 680U 4V(20%,ESR5,7343,TAN)H3.8'              | 'SMT'          | ''          | ''            | '20140527'
 '680UF'  | '4V'    | '20%'       | 'SMLF'      | 'EMPTY'    | 'CH7680KMT80'(!)             = ''              | ''                 | 'CH7680KMT80'                |'TAJ_D4'| '680UF'  | '4V'          | '20%'       | 'IO'       | 'CAP CHIP 680U 4V(20%,ESR5,7343,TAN)H3.8'              | 'SMT'          | ''          | ''            | '20140527'
 '10UF'   | '100V'  | '20%'       | 'SMLF'      | 'ALUM'     | 'CC61008MZ01'(!)             = ''              | ''                 | 'CC61008MZ01'                |'EC75_248_303S'| '10UF'   | '100V'        | '20%'       | 'DISCRETE' | 'CAP ELEC 10U 100V(+-20%,105C,6.3*7.7)'                | 'SMT'          | ''          | ''            | '2010722' 
 '10UF'   | '100V'  | '20%'       | 'SMLF'      | 'EMPTY'    | 'CC61008MZ01'(!)             = ''              | ''                 | 'CC61008MZ01'                |'EC75_248_303S'| '10UF'   | '100V'        | '20%'       | 'IO'       | 'CAP ELEC 10U 100V(+-20%,105C,6.3*7.7)'                | 'SMT'          | ''          | ''            | '2010722' 
 '330UF'  | '16V'   | '20%'       | 'SMLF'      | 'TANT'     | 'CH7333MT800'(!)             = 'Potential'     | 'End of Life'      | 'CH7333MT800'                |'TAJ_D4_EOL'| '330UF'  | '16V'         | '20%'       | 'DISCRETE' | 'CAP CHIP 330U 16V(+-20%,TAN,7343,H4.0)'               | 'SMT'          | ''          | ''            | '20140731'
 '330UF'  | '16V'   | '20%'       | 'SMLF'      | 'EMPTY'    | 'CH7333MT800'(!)             = 'Potential'     | 'End of Life'      | 'CH7333MT800'                |'TAJ_D4_EOL'| '330UF'  | '16V'         | '20%'       | 'IO'       | 'CAP CHIP 330U 16V(+-20%,TAN,7343,H4.0)'               | 'SMT'          | ''          | ''            | '20140731'
 '220UF'  | '100V'  | '20%'       | 'RDLF'      | 'ALUM'     | 'CC72208MD02'(!)             = ''              | ''                 | 'CC72208MD02'                |'EC197_493_985'| '220UF'  | '100V'        | '20%'       | 'DISCRETE' | 'CAPELECDIP 220U 100V(20%,ESR0.06,12.5*25'             | 'DIP'          | ''          | ''            | '20140806'
 '220UF'  | '100V'  | '20%'       | 'RDLF'      | 'EMPTY'    | 'CC72208MD02'(!)             = ''              | ''                 | 'CC72208MD02'                |'EC197_493_985'| '220UF'  | '100V'        | '20%'       | 'IO'       | 'CAPELECDIP 220U 100V(20%,ESR0.06,12.5*25'             | 'DIP'          | ''          | ''            | '20140806'
 '560UF'  | '2.5V'  | '20%'       | 'RDLF'      | 'ALUM'     | 'CC7560JMD11'(!)             = ''              | 'End of Life'      | 'CC7560JMD11'                |'EC98_248_237_EOL'| '560UF'  | '2.5V'        | '20%'       | 'DISCRETE' | 'CAP ELEC DIP 560U 2.5V(20%,105C,6.3*6)'               | 'DIP'          | ''          | ''            | '20140806'
 '560UF'  | '2.5V'  | '20%'       | 'RDLF'      | 'EMPTY'    | 'CC7560JMD11'(!)             = ''              | 'End of Life'      | 'CC7560JMD11'                |'EC98_248_237_EOL'| '560UF'  | '2.5V'        | '20%'       | 'IO'       | 'CAP ELEC DIP 560U 2.5V(20%,105C,6.3*6)'               | 'DIP'          | ''          | ''            | '20140806'
 '470UF'  | '2V'    | '20%'       | 'SMLF'      | 'TANT'     | 'CH747RM8807'(!)             = 'End of Design' | 'Comp-Approve'     | 'CH747RM8807'                |'TAJ_LX'| '470UF'  | '2V'          | '20%'       | 'DISCRETE' | 'CAP CHIP 470U 2V(20%,ESR4.5,7343,H1.9)3P'             | 'SMT'          | ''          | ''            | '20140813'
 '470UF'  | '2V'    | '20%'       | 'SMLF'      | 'EMPTY'    | 'CH747RM8807'(!)             = 'End of Design' | 'Comp-Approve'     | 'CH747RM8807'                |'TAJ_LX'| '470UF'  | '2V'          | '20%'       | 'IO'       | 'CAP CHIP 470U 2V(20%,ESR4.5,7343,H1.9)3P'             | 'SMT'          | ''          | ''            | '20140813'
 '270UF'  | '16V'   | '20%'       | 'SMLF'      | 'OSCON'    | 'CC72703MZ00'(!)             = ''              | ''                 | 'CC72703MZ00'                |'EC126_315_272S'| '270UF'  | '16V'         | '20%'       | 'DISCRETE' | 'CAP OSCON SMD 270U 16V(20%.105C.8*6.9)'               | 'SMT'          | ''          | ''            | '20140819'
 '270UF'  | '16V'   | '20%'       | 'SMLF'      | 'EMPTY'    | 'CC72703MZ00'(!)             = ''              | ''                 | 'CC72703MZ00'                |'EC126_315_272S'| '270UF'  | '16V'         | '20%'       | 'IO'       | 'CAP OSCON SMD 270U 16V(20%.105C.8*6.9)'               | 'SMT'          | ''          | ''            | '20140819'
 '22UF'   | '25V'   | '20%'       | 'SMLF'      | 'ALUM'     | 'CC62204MZ39'(!)             = ''              | ''                 | 'CC62204MZ39'                |'EC71_248_213S'| '22UF'   | '25V'         | '20%'       | 'DISCRETE' | 'CAP ELEC SMD 22U 25V(+-20%,85C,6.3*5.4)'              | 'SMT'          | ''          | ''            | '20140825'
 '22UF'   | '25V'   | '20%'       | 'SMLF'      | 'EMPTY'    | 'CC62204MZ39'(!)             = ''              | ''                 | 'CC62204MZ39'                |'EC71_248_213S'| '22UF'   | '25V'         | '20%'       | 'IO'       | 'CAP ELEC SMD 22U 25V(+-20%,85C,6.3*5.4)'              | 'SMT'          | ''          | ''            | '20140825'
 '100UF'  | '16V'   | '20%'       | 'SMLF'      | 'POSCAP'   | 'TH7103MI800'(!)             = ''              | ''                 | 'TH7103MI800'                |'TAJ_D2'| '100UF'  | '16V'         | '20%'       | 'DISCRETE' | 'CAP CHIP 100U 16V(20%,POSCAP,7343)EMSSEL'             | 'SMT'          | ''          | ''            | '20140825'
 '100UF'  | '16V'   | '20%'       | 'SMLF'      | 'EMPTY'    | 'TH7103MI800'(!)             = ''              | ''                 | 'TH7103MI800'                |'TAJ_D2'| '100UF'  | '16V'         | '20%'       | 'IO'       | 'CAP CHIP 100U 16V(20%,POSCAP,7343)EMSSEL'             | 'SMT'          | ''          | ''            | '20140825'
 '270UF'  | '16V'   | '20%'       | 'RDLF'      | 'ALUM'     | 'CC72703MD23'(!)             = ''              | ''                 | 'CC72703MD23'                |'EC2-5_6-8_9'| '270UF'  | '16V'         | '20%'       | 'DISCRETE' | 'CAP ELEC DIP 270U 16V(20% ESR9.5 6.3*9)'              | 'DIP'          | ''          | ''            | '20140827'
 '270UF'  | '16V'   | '20%'       | 'RDLF'      | 'EMPTY'    | 'CC72703MD23'(!)             = ''              | ''                 | 'CC72703MD23'                |'EC2-5_6-8_9'| '270UF'  | '16V'         | '20%'       | 'IO'       | 'CAP ELEC DIP 270U 16V(20% ESR9.5 6.3*9)'              | 'DIP'          | ''          | ''            | '20140827'
 '560UF'  | '6.3V'  | '20%'       | 'RDLF'      | 'ALUM'     | 'CC75601MD12'(!)             = ''              | ''                 | 'CC75601MD12'                |'EC98_248_354XA'| '560UF'  | '6.3V'        | '20%'       | 'DISCRETE' | 'CAP ELEC DIP 560U 6.3V(20% ESR6.5 6.3*9'              | 'DIP'          | ''          | ''            | '20140827'
 '560UF'  | '6.3V'  | '20%'       | 'RDLF'      | 'EMPTY'    | 'CC75601MD12'(!)             = ''              | ''                 | 'CC75601MD12'                |'EC98_248_354XA'| '560UF'  | '6.3V'        | '20%'       | 'IO'       | 'CAP ELEC DIP 560U 6.3V(20% ESR6.5 6.3*9'              | 'DIP'          | ''          | ''            | '20140827'
 '820UF'  | '2.5V'  | '20%'       | 'RDLF'      | 'ALUM'     | 'CC7820JMD10'(!)             = ''              | ''                 | 'CC7820JMD10'                |'EC98_248_354'| '820UF'  | '2.5V'        | '20%'       | 'DISCRETE' | 'CAP ELEC DIP 820U 2.5V(20% ESR6.5 6.3*9'              | 'DIP'          | ''          | ''            | '20140827'
 '820UF'  | '2.5V'  | '20%'       | 'RDLF'      | 'EMPTY'    | 'CC7820JMD10'(!)             = ''              | ''                 | 'CC7820JMD10'                |'EC98_248_354'| '820UF'  | '2.5V'        | '20%'       | 'IO'       | 'CAP ELEC DIP 820U 2.5V(20% ESR6.5 6.3*9'              | 'DIP'          | ''          | ''            | '20140827'
 '560UF'  | '2.5V'  | '20%'       | 'RDLF'      | 'ALUM'     | 'CC7560JMD12'(!)             = ''              | ''                 | 'CC7560JMD12'                |'EC2_5-5_9XB'| '560UF'  | '2.5V'        | '20%'       | 'DISCRETE' | 'CAP ELEC DIP 560U 2.5V(20% ESR6.5 5*9)'               | 'DIP'          | ''          | ''            | '20140827'
 '560UF'  | '2.5V'  | '20%'       | 'RDLF'      | 'EMPTY'    | 'CC7560JMD12'(!)             = ''              | ''                 | 'CC7560JMD12'                |'EC2_5-5_9XB'| '560UF'  | '2.5V'        | '20%'       | 'IO'       | 'CAP ELEC DIP 560U 2.5V(20% ESR6.5 5*9)'               | 'DIP'          | ''          | ''            | '20140827'
 '100UF'  | '100V'  | '20%'       | 'RDLF'      | 'ALUM'     | 'CC71008MD06'(!)             = ''              | ''                 | 'CC71008MD06'                |'EC197_493_630'| '100UF'  | '100V'        | '20%'       | 'DISCRETE' | 'CAPELECDIP 100U 100V(20%,ESR0.13,12.5*16'             | 'DIP'          | ''          | ''            | '20140915'
 '100UF'  | '100V'  | '20%'       | 'RDLF'      | 'EMPTY'    | 'CC71008MD06'(!)             = ''              | ''                 | 'CC71008MD06'                |'EC197_493_630'| '100UF'  | '100V'        | '20%'       | 'IO'       | 'CAPELECDIP 100U 100V(20%,ESR0.13,12.5*16'             | 'DIP'          | ''          | ''            | '20140915'
 '100UF'  | '100V'  | '20%'       | 'RDLF_SEL'  | 'ALUM'     | 'SP_CC71008MD06'(!)          = ''              | ''                 | 'CC71008MD06'                |'G_EC197_493_630'| '100UF'  | '100V'        | '20%'       | 'DISCRETE' | 'CAPELECDIP 100U 100V(20%,ESR0.13,12.5*16'             | 'DIP'          | ''          | ''            | '20140915'
 '100UF'  | '100V'  | '20%'       | 'RDLF_SEL'  | 'EMPTY'    | 'SP_CC71008MD06'(!)          = ''              | ''                 | 'CC71008MD06'                |'G_EC197_493_630'| '100UF'  | '100V'        | '20%'       | 'IO'       | 'CAPELECDIP 100U 100V(20%,ESR0.13,12.5*16'             | 'DIP'          | ''          | ''            | '20140915'
 '0.33F'  | '5.5V'  | '30%'       | 'RDLF'      | 'ALUM'     | 'CCA3300TD01'(!)             = ''              | ''                 | 'CCA3300TD01'                |'EC197_394'| '0.33F'  | '5.5V'        | '30%'       | 'DISCRETE' | 'CAP ELEC DIP 0.33F 5.5V(30%,85C,11.5*5)'              | 'DIP'          | ''          | ''            | '20141006'
 '0.33F'  | '5.5V'  | '30%'       | 'RDLF'      | 'EMPTY'    | 'CCA3300TD01'(!)             = ''              | ''                 | 'CCA3300TD01'                |'EC197_394'| '0.33F'  | '5.5V'        | '30%'       | 'IO'       | 'CAP ELEC DIP 0.33F 5.5V(30%,85C,11.5*5)'              | 'DIP'          | ''          | ''            | '20141006'
 '560UF'  | '2.5V'  | '20%'       | 'RDLF_SEL'  | 'OSCON'    | 'CC7560JMD05'(!)             = ''              | ''                 | 'CC7560JMD05'                |'G_EC78_197_355'| '560UF'  | '2.5V'        | '20%'       | 'DISCRETE' | 'CAPOSCONDIP560U 2.5V(20%.105C.5*8)SELASS'             | 'DIP'          | ''          | ''            | '20150310'
 '560UF'  | '2.5V'  | '20%'       | 'RDLF_SEL'  | 'EMPTY'    | 'CC7560JMD05'(!)             = ''              | ''                 | 'CC7560JMD05'                |'G_EC78_197_355'| '560UF'  | '2.5V'        | '20%'       | 'IO'       | 'CAPOSCONDIP560U 2.5V(20%.105C.5*8)SELASS'             | 'DIP'          | ''          | ''            | '20150310'
 '820UF'  | '2.5V'  | '20%'       | 'RDLF'      | 'ALUM'     | 'CC7820JMD12'(!)             = 'Potential'     | 'End of Life'      | 'CC7820JMD12'                |'EC98_248_354_EOL'| '820UF'  | '2.5V'        | '20%'       | 'DISCRETE' | 'CAP ELEC DIP 820U 2.5V(20% ESR6.5 6.3*9'              | 'DIP'          | ''          | ''            | '20150319'
 '820UF'  | '2.5V'  | '20%'       | 'RDLF'      | 'EMPTY'    | 'CC7820JMD12'(!)             = 'Potential'     | 'End of Life'      | 'CC7820JMD12'                |'EC98_248_354_EOL'| '820UF'  | '2.5V'        | '20%'       | 'IO'       | 'CAP ELEC DIP 820U 2.5V(20% ESR6.5 6.3*9'              | 'DIP'          | ''          | ''            | '20150319'
 '560UF'  | '6.3V'  | '20%'       | 'RDLF'      | 'ALUM'     | 'CC75601MD14'(!)             = 'Potential'     | 'End of Life'      | 'CC75601MD14'                |'EC98_248_354_EOL'| '560UF'  | '6.3V'        | '20%'       | 'DISCRETE' | 'CAP ELEC DIP 560U 6.3V(20% ESR6.5 6.3*9'              | 'DIP'          | ''          | ''            | '20150319'
 '560UF'  | '6.3V'  | '20%'       | 'RDLF'      | 'EMPTY'    | 'CC75601MD14'(!)             = 'Potential'     | 'End of Life'      | 'CC75601MD14'                |'EC98_248_354_EOL'| '560UF'  | '6.3V'        | '20%'       | 'IO'       | 'CAP ELEC DIP 560U 6.3V(20% ESR6.5 6.3*9'              | 'DIP'          | ''          | ''            | '20150319'
 '270UF'  | '16V'   | '20%'       | 'RDLF'      | 'ALUM'     | 'CC72703MD24'(!)             = 'Potential'     | 'End of Life'      | 'CC72703MD24'                |'EC98_248_354_EOL'| '270UF'  | '16V'         | '20%'       | 'DISCRETE' | 'CAP ELEC DIP 270U 16V(20% ESR9.5 6.3*9)'              | 'DIP'          | ''          | ''            | '20150319'
 '270UF'  | '16V'   | '20%'       | 'RDLF'      | 'EMPTY'    | 'CC72703MD24'(!)             = 'Potential'     | 'End of Life'      | 'CC72703MD24'                |'EC98_248_354_EOL'| '270UF'  | '16V'         | '20%'       | 'IO'       | 'CAP ELEC DIP 270U 16V(20% ESR9.5 6.3*9)'              | 'DIP'          | ''          | ''            | '20150319'
 '220UF'  | '100V'  | '20%'       | 'SMLF'      | 'ALUM'     | 'CC72208MZ00'(!)             = ''              | ''                 | 'CC72208MZ00'                |'EC248_630_847S'| '220UF'  | '100V'        | '20%'       | 'DISCRETE' | 'CAP ELEC SMD 220U 100V(+-20%,16*21.5)'                | 'SMT'          | ''          | ''            | '20150413'
 '220UF'  | '100V'  | '20%'       | 'SMLF'      | 'EMPTY'    | 'CC72208MZ00'(!)             = ''              | ''                 | 'CC72208MZ00'                |'EC248_630_847S'| '220UF'  | '100V'        | '20%'       | 'IO'       | 'CAP ELEC SMD 220U 100V(+-20%,16*21.5)'                | 'SMT'          | ''          | ''            | '20150413'
 '560UF'  | '10V'   | '20%'       | 'SMLF'      | 'ALUM'     | 'CC75602MZ00'(!)             = ''              | ''                 | 'CC75602MZ00'                |'EC181_394_496S'| '560UF'  | '10V'         | '20%'       | 'DISCRETE' | 'CAP SMD 560U 10V(20%,105C,10.3*10.3)'                 | 'SMT'          | ''          | ''            | '20150414'
 '560UF'  | '10V'   | '20%'       | 'SMLF'      | 'EMPTY'    | 'CC75602MZ00'(!)             = ''              | ''                 | 'CC75602MZ00'                |'EC181_394_496S'| '560UF'  | '10V'         | '20%'       | 'IO'       | 'CAP SMD 560U 10V(20%,105C,10.3*10.3)'                 | 'SMT'          | ''          | ''            | '20150414'
 '270UF'  | '16V'   | '20%'       | 'SMLF'      | 'ALUM'     | 'CC72703MZ02'(!)             = 'End of Design' | 'Comp-Approve'     | 'CC72703MZ02'                |'EC83_248_390S'| '270UF'  | '16V'         | '20%'       | 'DISCRETE' | 'CAP OSCON SMD 270U 16V(20%,105C,6.3*9.9)'             | 'SMT'          | ''          | ''            | '20150420'
 '270UF'  | '16V'   | '20%'       | 'SMLF'      | 'EMPTY'    | 'CC72703MZ02'(!)             = 'End of Design' | 'Comp-Approve'     | 'CC72703MZ02'                |'EC83_248_390S'| '270UF'  | '16V'         | '20%'       | 'IO'       | 'CAP OSCON SMD 270U 16V(20%,105C,6.3*9.9)'             | 'SMT'          | ''          | ''            | '20150420'
 '560UF'  | '2.5V'  | '20%'       | 'RDLF'      | 'ALUM'     | 'CC7560JMD13'(!)             = 'Potential'     | 'End of Life'      | 'CC7560JMD13'                |'EC78_197_355_EOL'| '560UF'  | '2.5V'        | '20%'       | 'DISCRETE' | 'CAP ELEC DIP 560U 2.5V(20% ESR6.5 5*9)'               | 'DIP'          | ''          | ''            | '20150504'
 '560UF'  | '2.5V'  | '20%'       | 'RDLF'      | 'EMPTY'    | 'CC7560JMD13'(!)             = 'Potential'     | 'End of Life'      | 'CC7560JMD13'                |'EC78_197_355_EOL'| '560UF'  | '2.5V'        | '20%'       | 'IO'       | 'CAP ELEC DIP 560U 2.5V(20% ESR6.5 5*9)'               | 'DIP'          | ''          | ''            | '20150504'
 '470UF'  | '2V'    | '20%'       | 'SMLF'      | 'POSCAP'   | 'CH747RM8822'(!)             = ''              | ''                 | 'CH747RM8822'                |'TAJ_DXC'| '470UF'  | '2V'          | '20%'       | 'DISCRETE' | 'CAP CHIP 470U 2V(+-20%,SPCAP,7343)MAT'                | 'SMT'          | ''          | ''            | '20150613'
 '470UF'  | '2V'    | '20%'       | 'SMLF'      | 'EMPTY'    | 'CH747RM8822'(!)             = ''              | ''                 | 'CH747RM8822'                |'TAJ_DXC'| '470UF'  | '2V'          | '20%'       | 'IO'       | 'CAP CHIP 470U 2V(+-20%,SPCAP,7343)MAT'                | 'SMT'          | ''          | ''            | '20150613'
 '100UF'  | '16V'   | '20%'       | 'RDLF'      | 'OSCON'    | 'CC71003MD14'(!)             = ''              | ''                 | 'CC71003MD14'                |'EC98_248_237'| '100UF'  | '16V'         | '20%'       | 'DISCRETE' | 'CAP OSCON DIP 100U 16V(20%,6.3*6)TOW'                 | 'DIP'          | ''          | ''            | '20150613'
 '100UF'  | '16V'   | '20%'       | 'RDLF'      | 'EMPTY'    | 'CC71003MD14'(!)             = ''              | ''                 | 'CC71003MD14'                |'EC98_248_237'| '100UF'  | '16V'         | '20%'       | 'IO'       | 'CAP OSCON DIP 100U 16V(20%,6.3*6)TOW'                 | 'DIP'          | ''          | ''            | '20150613'
 '100UF'  | '16V'   | '20%'       | 'RDLF'      | 'OSCON'    | 'SP_CC71003MD14'(!)          = ''              | ''                 | 'CC71003MD14'                |'G_EC98_248_237'| '100UF'  | '16V'         | '20%'       | 'DISCRETE' | 'CAP OSCON DIP 100U 16V(20%,6.3*6)TOW_FOR SEL'         | 'DIP'          | ''          | ''            | '20150613'
 '100UF'  | '16V'   | '20%'       | 'RDLF'      | 'EMPTY'    | 'SP_CC71003MD14'(!)          = ''              | ''                 | 'CC71003MD14'                |'G_EC98_248_237'| '100UF'  | '16V'         | '20%'       | 'IO'       | 'CAP OSCON DIP 100U 16V(20%,6.3*6)TOW_FOR SEL'         | 'DIP'          | ''          | ''            | '20150613'
 '100UF'  | '16V'   | '20%'       | 'SMLF'      | 'POSCAP'   | 'CH7103M8804'(!)             = 'End of Design' | 'Comp-Approve'     | 'CH7103M8804'                |'TAJ_D9'| '100UF'  | '16V'         | '20%'       | 'DISCRETE' | 'CAP CHIP 100UF 16V(20%,SPCAP,7343)MUR'                | 'SMT'          | ''          | ''            | '20150615'
 '100UF'  | '16V'   | '20%'       | 'SMLF'      | 'EMPTY'    | 'CH7103M8804'(!)             = 'End of Design' | 'Comp-Approve'     | 'CH7103M8804'                |'TAJ_D9'| '100UF'  | '16V'         | '20%'       | 'IO'       | 'CAP CHIP 100UF 16V(20%,SPCAP,7343)MUR'                | 'SMT'          | ''          | ''            | '20150615'
 '100UF'  | '100V'  | '20%'       | 'RDLF'      | 'ALUM'     | 'CC71008MD08'(!)             = ''              | ''                 | 'CC71008MD08'                |'EC197_394_787'| '100UF'  | '100V'        | '20%'       | 'DISCRETE' | 'CAP ELEC DIP 100U 100V(20%,10*20)RBN'                 | 'DIP'          | ''          | ''            | '20150615'
 '100UF'  | '100V'  | '20%'       | 'RDLF'      | 'EMPTY'    | 'CC71008MD08'(!)             = ''              | ''                 | 'CC71008MD08'                |'EC197_394_787'| '100UF'  | '100V'        | '20%'       | 'IO'       | 'CAP ELEC DIP 100U 100V(20%,10*20)RBN'                 | 'DIP'          | ''          | ''            | '20150615'
 '100UF'  | '100V'  | '20%'       | 'RDLF'      | 'ALUM'     | 'SP_CC71008MD08'(!)          = ''              | ''                 | 'CC71008MD08'                |'G_EC197_394_787'| '100UF'  | '100V'        | '20%'       | 'DISCRETE' | 'CAP ELEC DIP 100U 100V(20%,10*20)RBN_FOR SEL'         | 'DIP'          | ''          | ''            | '20150615'
 '100UF'  | '100V'  | '20%'       | 'RDLF'      | 'EMPTY'    | 'SP_CC71008MD08'(!)          = ''              | ''                 | 'CC71008MD08'                |'G_EC197_394_787'| '100UF'  | '100V'        | '20%'       | 'IO'       | 'CAP ELEC DIP 100U 100V(20%,10*20)RBN_FOR SEL'         | 'DIP'          | ''          | ''            | '20150615'
 '220UF'  | '10V'   | '20%'       | 'SMLF'      | 'POSCAP'   | 'CH7222MI801'(!)             = ''              | ''                 | 'CH7222MI801'                |'TAJ_D3L'| '220UF'  | '10V'         | '20%'       | 'DISCRETE' | 'CAP CHIP 220U 10V(20%,POSCAP,7343)SAY'                | 'SMT'          | ''          | ''            | '20150618'
 '220UF'  | '10V'   | '20%'       | 'SMLF'      | 'EMPTY'    | 'CH7222MI801'(!)             = ''              | ''                 | 'CH7222MI801'                |'TAJ_D3L'| '220UF'  | '10V'         | '20%'       | 'IO'       | 'CAP CHIP 220U 10V(20%,POSCAP,7343)SAY'                | 'SMT'          | ''          | ''            | '20150618'
 '47UF'   | '16V'   | '20%'       | 'SMLF'      | 'POSCAP'   | 'CH6473M8802'(!)             = ''              | 'Comp-Release Qty' | 'CH6473M8802'                | 'TAJ_DXC'                  | '47UF'   | '16V'         | '20%'       | 'DISCRETE' | 'CAP CHIP 47U 16V(+-20%,ESR=40,7343)SPCAP'             | 'SMT'          | ''          | ''            | '20150709'
 '47UF'   | '16V'   | '20%'       | 'SMLF'      | 'EMPTY'    | 'CH6473M8802'(!)             = ''              | 'Comp-Release Qty' | 'CH6473M8802'                | 'TAJ_DXC'                  | '47UF'   | '16V'         | '20%'       | 'IO'       | 'CAP CHIP 47U 16V(+-20%,ESR=40,7343)SPCAP'             | 'SMT'          | ''          | ''            | '20150709'
 '0.011F' | '3.3V'  | '18%'       | 'SMLF'      | ''         | 'CC9110KTZ00'(!)             = ''              | ''                 | 'CC9110KTZ00'                |'EC1210'| '0.011F' | '3.3V'        | '18%'       | 'DISCRETE' | 'CAP ELEC SMD 0.011F 3.3V(18%,3.2*2.5)'                | 'SMT'          | ''          | ''            | '20150728'
 '0.011F' | '3.3V'  | '18%'       | 'SMLF'      | 'EMPTY'    | 'CC9110KTZ00'(!)             = ''              | ''                 | 'CC9110KTZ00'                |'EC1210'| '0.011F' | '3.3V'        | '18%'       | 'IO'       | 'CAP ELEC SMD 0.011F 3.3V(18%,3.2*2.5)'                | 'SMT'          | ''          | ''            | '20150728'
 '100UF'  | '16V'   | '20%'       | 'SMLF'      | 'ALUM'     | 'CC71003MZ26'(!)             = ''              | ''                 | 'CC71003MZ26'                |'EC56_197_229S'| '100UF'  | '16V'         | '20%'       | 'DISCRETE' | 'CAP OSCON SMD 100U 16V(20%,ESR26,5*5.8)'              | 'SMT'          | ''          | ''            | '20150807'
 '100UF'  | '16V'   | '20%'       | 'SMLF'      | 'EMPTY'    | 'CC71003MZ26'(!)             = ''              | ''                 | 'CC71003MZ26'                |'EC56_197_229S'| '100UF'  | '16V'         | '20%'       | 'IO'       | 'CAP OSCON SMD 100U 16V(20%,ESR26,5*5.8)'              | 'SMT'          | ''          | ''            | '20150807'
 '180UF'  | '16V'   | '20%'       | 'SMLF'      | 'ALUM'     | 'CC71803MZ06'(!)             = ''              | ''                 | 'CC71803MZ06'                |'EC83_248_229S'| '180UF'  | '16V'         | '20%'       | 'DISCRETE' | 'CAP OSCON SMD 180U 16V(20%,ESR21,6.3*5.8'             | 'SMT'          | ''          | ''            | '20150807'
 '180UF'  | '16V'   | '20%'       | 'SMLF'      | 'EMPTY'    | 'CC71803MZ06'(!)             = ''              | ''                 | 'CC71803MZ06'                |'EC83_248_229S'| '180UF'  | '16V'         | '20%'       | 'IO'       | 'CAP OSCON SMD 180U 16V(20%,ESR21,6.3*5.8'             | 'SMT'          | ''          | ''            | '20150807'
 '560UF'  | '2.5V'  | '20%'       | 'RDLF'      | 'OSCON'    | 'CC7560JMD14'(!)             = 'Potential'     | 'End of Life'      | 'CC7560JMD14'                |'EC78_197_315_EOL'| '560UF'  | '2.5V'        | '20%'       | 'DISCRETE' | 'CAP OSCON DIP 560U 2.5V(20%,5*8)TOW'                  | 'DIP'          | ''          | ''            | '20150810'
 '560UF'  | '2.5V'  | '20%'       | 'RDLF'      | 'EMPTY'    | 'CC7560JMD14'(!)             = 'Potential'     | 'End of Life'      | 'CC7560JMD14'                |'EC78_197_315_EOL'| '560UF'  | '2.5V'        | '20%'       | 'IO'       | 'CAP OSCON DIP 560U 2.5V(20%,5*8)TOW'                  | 'DIP'          | ''          | ''            | '20150810'
 '560UF'  | '2.5V'  | '20%'       | 'RDLF'      | 'OSCON'    | 'SP_CC7560JMD14'(!)          = 'Potential'     | 'End of Life'      | 'CC7560JMD14'                |'G_EC78_197_315_EOL'| '560UF'  | '2.5V'        | '20%'       | 'DISCRETE' | 'CAP OSCON DIP 560U 2.5V(20%,5*8)TOW_FOR SEL'          | 'DIP'          | ''          | ''            | '20150810'
 '560UF'  | '2.5V'  | '20%'       | 'RDLF'      | 'EMPTY'    | 'SP_CC7560JMD14'(!)          = 'Potential'     | 'End of Life'      | 'CC7560JMD14'                |'G_EC78_197_315_EOL'| '560UF'  | '2.5V'        | '20%'       | 'IO'       | 'CAP OSCON DIP 560U 2.5V(20%,5*8)TOW_FOR SEL'          | 'DIP'          | ''          | ''            | '20150810'
 '100UF'  | '16V'   | '20%'       | 'SMLF'      | 'OSCON'    | 'CC71003MZ28'(!)             = ''              | ''                 | 'CC71003MZ28'                |'EC83_248_232S'| '100UF'  | '16V'         | '20%'       | 'DISCRETE' | 'CAP OSCON SMD 100U 16V(20%,6.3*5.9)SAY'               | 'SMT'          | ''          | ''            | '20150826'
 '100UF'  | '16V'   | '20%'       | 'SMLF'      | 'EMPTY'    | 'CC71003MZ28'(!)             = ''              | ''                 | 'CC71003MZ28'                |'EC83_248_232S'| '100UF'  | '16V'         | '20%'       | 'IO'       | 'CAP OSCON SMD 100U 16V(20%,6.3*5.9)SAY'               | 'SMT'          | ''          | ''            | '20150826'
 '390UF'  | '2.5V'  | '20%'       | 'SMLF'      | 'OSCON'    | 'CC7390JMZ11'(!)             = ''              | ''                 | 'CC7390JMZ11'                |'EC56_197_233S'| '390UF'  | '2.5V'        | '20%'       | 'DISCRETE' | 'CAP OSCON SMD 390U 2.5V(20%,5*5.9)SAY'                | 'SMT'          | ''          | ''            | '20150826'
 '390UF'  | '2.5V'  | '20%'       | 'SMLF'      | 'EMPTY'    | 'CC7390JMZ11'(!)             = ''              | ''                 | 'CC7390JMZ11'                |'EC56_197_233S'| '390UF'  | '2.5V'        | '20%'       | 'IO'       | 'CAP OSCON SMD 390U 2.5V(20%,5*5.9)SAY'                | 'SMT'          | ''          | ''            | '20150826'
 '10UF'   | '100V'  | '20%'       | 'SMLF'      | 'ALUM'     | 'CC61008MZ02'(!)             = ''              | ''                 | 'CC61008MZ02'                |'EC75_248_303S_EOL'| '10UF'   | '100V'        | '20%'       | 'DISCRETE' | 'CAP ELEC 10U 100V(+-20%,105C,6.3*7.7)NPN'             | 'SMT'          | ''          | ''            | '20151022'
 '10UF'   | '100V'  | '20%'       | 'SMLF'      | 'EMPTY'    | 'CC61008MZ02'(!)             = ''              | ''                 | 'CC61008MZ02'                |'EC75_248_303S_EOL'| '10UF'   | '100V'        | '20%'       | 'IO'       | 'CAP ELEC 10U 100V(+-20%,105C,6.3*7.7)NPN'             | 'SMT'          | ''          | ''            | '20151022'
 '330UF'  | '16V'   | '20%'       | 'SMLF'      | 'ALUM'     | 'CC73303MZ01'(!)             = 'End of Design' | 'Comp-Approve'     | 'CC73303MZ01'                |'EC178_394_394S'| '330UF'  | '16V'         | '20%'       | 'DISCRETE' | 'CAP OSCON 330U 16V (20%,105C,10*10)NPN'               | 'SMT'          | ''          | ''            | '20151022'
 '330UF'  | '16V'   | '20%'       | 'SMLF'      | 'EMPTY'    | 'CC73303MZ01'(!)             = 'End of Design' | 'Comp-Approve'     | 'CC73303MZ01'                |'EC178_394_394S'| '330UF'  | '16V'         | '20%'       | 'IO'       | 'CAP OSCON 330U 16V (20%,105C,10*10)NPN'               | 'SMT'          | ''          | ''            | '20151022'
 '100UF'  | '16V'   | '20%'       | 'SMLF'      | 'ALUM'     | 'CC71003MZ29'(!)             = ''              | ''                 | 'CC71003MZ29'                |'EC75_248_229SXA'| '100UF'  | '16V'         | '20%'       | 'DISCRETE' | 'CAP OSCON SMD 100U 16V(20%,6.3*5.8)NPN'               | 'SMT'          | ''          | ''            | '20151022'
 '100UF'  | '16V'   | '20%'       | 'SMLF'      | 'EMPTY'    | 'CC71003MZ29'(!)             = ''              | ''                 | 'CC71003MZ29'                |'EC75_248_229SXA'| '100UF'  | '16V'         | '20%'       | 'IO'       | 'CAP OSCON SMD 100U 16V(20%,6.3*5.8)NPN'               | 'SMT'          | ''          | ''            | '20151022'
 '100UF'  | '16V'   | '20%'       | 'THLF'      | 'ALUM'     | 'CC71003MD17'(!)             = ''              | ''                 | 'CC71003MD17'                |'EC2-5_6-8_6'| '100UF'  | '16V'         | '20%'       | 'DISCRETE' | 'CAP OSCON DIP 100U 16V(20%,6.3*6)NPN'                 | 'DIP'          | ''          | ''            | '20151022'
 '100UF'  | '16V'   | '20%'       | 'THLF'      | 'EMPTY'    | 'CC71003MD17'(!)             = ''              | ''                 | 'CC71003MD17'                |'EC2-5_6-8_6'| '100UF'  | '16V'         | '20%'       | 'IO'       | 'CAP OSCON DIP 100U 16V(20%,6.3*6)NPN'                 | 'DIP'          | ''          | ''            | '20151022'
 '100UF'  | '20V'   | '20%'       | 'SMLF'      | 'POSCAP'   | 'CH710BMI803'(!)             = ''              | ''                 | 'CH710BMI803'                |'TAJ_D3L'| '100UF'  | '20V'         | '20%'       | 'DISCRETE' | 'CAP 100U 20V(20%,POSCAP,ESR55,7343)SAY'               | 'SMT'          | ''          | ''            | '20151022'
 '100UF'  | '20V'   | '20%'       | 'SMLF'      | 'EMPTY'    | 'CH710BMI803'(!)             = ''              | ''                 | 'CH710BMI803'                |'TAJ_D3L'| '100UF'  | '20V'         | '20%'       | 'IO'       | 'CAP 100U 20V(20%,POSCAP,ESR55,7343)SAY'               | 'SMT'          | ''          | ''            | '20151022'
 '180UF'  | '20V'   | '20%'       | 'SMLF'      | 'ALUM'     | 'CC7180HMZ00'(!)             = ''              | ''                 | 'CC7180HMZ00'                |'EC126_315_272S'| '180UF'  | '20V'         | '20%'       | 'DISCRETE' | 'CAP OS-CON 180U 20V(20%.105C.8*6.9)SMD'               | 'SMT'          | ''          | ''            | '20151123'
 '180UF'  | '20V'   | '20%'       | 'SMLF'      | 'EMPTY'    | 'CC7180HMZ00'(!)             = ''              | ''                 | 'CC7180HMZ00'                |'EC126_315_272S'| '180UF'  | '20V'         | '20%'       | 'IO'       | 'CAP OS-CON 180U 20V(20%.105C.8*6.9)SMD'               | 'SMT'          | ''          | ''            | '20151123'
 '330UF'  | '6.3V'  | '20%'       | 'SMLF'      | 'TANT'     | 'CH7331M8805'(!)             = 'End of Design' | 'Comp-Approve'     | 'CH7331M8805'                |'TAJ_D3L'| '330UF'  | '6.3V'        | '20%'       | 'DISCRETE' | 'CAP CHIP 330U 6.3V 20% ESR10(7343)POSCAP'             | 'SMT'          | ''          | ''            | '20151123'
 '330UF'  | '6.3V'  | '20%'       | 'SMLF'      | 'EMPTY'    | 'CH7331M8805'(!)             = 'End of Design' | 'Comp-Approve'     | 'CH7331M8805'                |'TAJ_D3L'| '330UF'  | '6.3V'        | '20%'       | 'IO'       | 'CAP CHIP 330U 6.3V 20% ESR10(7343)POSCAP'             | 'SMT'          | ''          | ''            | '20151123'
 '330UF'  | '6.3V'  | '20%'       | 'SMLF'      | 'TANT'     | 'CH7331M8819'(!)             = ''              | ''                 | 'CH7331M8819'                |'TAJ_D3L'| '330UF'  | '6.3V'        | '20%'       | 'DISCRETE' | 'CAP CHIP 330U 6.3V(+-20%,POSCAP,7343)'                | 'SMT'          | ''          | ''            | '20151123'
 '330UF'  | '6.3V'  | '20%'       | 'SMLF'      | 'EMPTY'    | 'CH7331M8819'(!)             = ''              | ''                 | 'CH7331M8819'                |'TAJ_D3L'| '330UF'  | '6.3V'        | '20%'       | 'IO'       | 'CAP CHIP 330U 6.3V(+-20%,POSCAP,7343)'                | 'SMT'          | ''          | ''            | '20151123'
 '270UF'  | '16V'   | '20%'       | 'RDLF'      | 'OSCON'    | 'SP_CC72703MD26_1'(!)        = ''              | ''                 | 'CC72703MD26'                |'G_EC138_315_315_UH3M'| '270UF'  | '16V'         | '20%'       | 'DISCRETE' | 'CAP OSCON DIP 270U 16V(+-20%,8*8)TOW_FOR SEL_UH3M'    | 'DIP'          | ''          | ''            | '20151215'
 '270UF'  | '16V'   | '20%'       | 'RDLF'      | 'EMPTY'    | 'SP_CC72703MD26_1'(!)        = ''              | ''                 | 'CC72703MD26'                |'G_EC138_315_315_UH3M'| '270UF'  | '16V'         | '20%'       | 'IO'       | 'CAP OSCON DIP 270U 16V(+-20%,8*8)TOW_FOR SEL_UH3M'    | 'DIP'          | ''          | ''            | '20151215'
 '100UF'  | '100V'  | '20%'       | 'RDLF'      | 'ALUM'     | 'SP_CC71008MD07_1'(!)        = ''              | ''                 | 'CC71008MD07'                |'G_EC197_394_787_UH3M'| '100UF'  | '100V'        | '20%'       | 'DISCRETE' | 'CAP ELEC DIP 100U 100V(20%,10*20)NPN_FOR SEL_UH3M'    | 'DIP'          | ''          | ''            | '20151215'
 '100UF'  | '100V'  | '20%'       | 'RDLF'      | 'EMPTY'    | 'SP_CC71008MD07_1'(!)        = ''              | ''                 | 'CC71008MD07'                |'G_EC197_394_787_UH3M'| '100UF'  | '100V'        | '20%'       | 'IO'       | 'CAP ELEC DIP 100U 100V(20%,10*20)NPN_FOR SEL_UH3M'    | 'DIP'          | ''          | ''            | '20151215'
 '560UF'  | '6.3V'  | '20%'       | 'RDLF'      | 'OSCON'    | 'SP_CC75601MD15_1'(!)        = ''              | ''                 | 'CC75601MD15'                |'G_EC98_248_315_UH3M'| '560UF'  | '6.3V'        | '20%'       | 'DISCRETE' | 'CAP OSCON DIP 560U 6.3V(+-20%,6.3*8)TOW_FOR SEL_UH3M' | 'DIP'          | ''          | ''            | '20151215'
 '560UF'  | '6.3V'  | '20%'       | 'RDLF'      | 'EMPTY'    | 'SP_CC75601MD15_1'(!)        = ''              | ''                 | 'CC75601MD15'                |'G_EC98_248_315_UH3M'| '560UF'  | '6.3V'        | '20%'       | 'IO'       | 'CAP OSCON DIP 560U 6.3V(+-20%,6.3*8)TOW_FOR SEL_UH3M' | 'DIP'          | ''          | ''            | '20151215'
 '100UF'  | '16V'   | '20%'       | 'RDLF'      | 'ALUM'     | 'SP_CC71003MD17'(!)          = ''              | ''                 | 'CC71003MD17'                |'G_EC98_248_237_UH3M'| '100UF'  | '16V'         | '20%'       | 'DISCRETE' | 'CAP OSCON DIP 100U 16V(20%,6.3*6)NPN_FOR SEL_UH3M'    | 'DIP'          | ''          | ''            | '20151215'
 '100UF'  | '16V'   | '20%'       | 'RDLF'      | 'EMPTY'    | 'SP_CC71003MD17'(!)          = ''              | ''                 | 'CC71003MD17'                |'G_EC98_248_237_UH3M'| '100UF'  | '16V'         | '20%'       | 'IO'       | 'CAP OSCON DIP 100U 16V(20%,6.3*6)NPN_FOR SEL_UH3M'    | 'DIP'          | ''          | ''            | '20151215'
 '560UF'  | '6.3V'  | '20%'       | 'RDLF'      | 'OSCON'    | 'CC75601MD15'(!)             = ''              | ''                 | 'CC75601MD15'                |'EC98_248_315'| '560UF'  | '6.3V'        | '20%'       | 'DISCRETE' | 'CAP OSCON DIP 560U 6.3V(+-20%,6.3*8)TOW'              | 'DIP'          | ''          | ''            | '20151215'
 '560UF'  | '6.3V'  | '20%'       | 'RDLF'      | 'EMPTY'    | 'CC75601MD15'(!)             = ''              | ''                 | 'CC75601MD15'                |'EC98_248_315'| '560UF'  | '6.3V'        | '20%'       | 'IO'       | 'CAP OSCON DIP 560U 6.3V(+-20%,6.3*8)TOW'              | 'DIP'          | ''          | ''            | '20151215'
 '560UF'  | '6.3V'  | '20%'       | 'RDLF'      | 'OSCON'    | 'SP_CC75601MD15'(!)          = ''              | ''                 | 'CC75601MD15'                |'G_EC98_248_315'| '560UF'  | '6.3V'        | '20%'       | 'DISCRETE' | 'CAP OSCON DIP 560U 6.3V(+-20%,6.3*8)TOW_FOR SEL'      | 'DIP'          | ''          | ''            | '20151215'
 '560UF'  | '6.3V'  | '20%'       | 'RDLF'      | 'EMPTY'    | 'SP_CC75601MD15'(!)          = ''              | ''                 | 'CC75601MD15'                |'G_EC98_248_315'| '560UF'  | '6.3V'        | '20%'       | 'IO'       | 'CAP OSCON DIP 560U 6.3V(+-20%,6.3*8)TOW_FOR SEL'      | 'DIP'          | ''          | ''            | '20151215'
 '270UF'  | '16V'   | '20%'       | 'RDLF'      | 'OSCON'    | 'CC72703MD26'(!)             = ''              | ''                 | 'CC72703MD26'                |'EC138_315_315'| '270UF'  | '16V'         | '20%'       | 'DISCRETE' | 'CAP OSCON DIP 270U 16V(+-20%,8*8)TOW'                 | 'DIP'          | ''          | ''            | '20151215'
 '270UF'  | '16V'   | '20%'       | 'RDLF'      | 'EMPTY'    | 'CC72703MD26'(!)             = ''              | ''                 | 'CC72703MD26'                |'EC138_315_315'| '270UF'  | '16V'         | '20%'       | 'IO'       | 'CAP OSCON DIP 270U 16V(+-20%,8*8)TOW'                 | 'DIP'          | ''          | ''            | '20151215'
 '270UF'  | '16V'   | '20%'       | 'RDLF'      | 'OSCON'    | 'SP_CC72703MD26'(!)          = ''              | ''                 | 'CC72703MD26'                |'G_EC138_315_315'| '270UF'  | '16V'         | '20%'       | 'DISCRETE' | 'CAP OSCON DIP 270U 16V(+-20%,8*8)TOW_FOR SEL'         | 'DIP'          | ''          | ''            | '20151215'
 '270UF'  | '16V'   | '20%'       | 'RDLF'      | 'EMPTY'    | 'SP_CC72703MD26'(!)          = ''              | ''                 | 'CC72703MD26'                |'G_EC138_315_315'| '270UF'  | '16V'         | '20%'       | 'IO'       | 'CAP OSCON DIP 270U 16V(+-20%,8*8)TOW_FOR SEL'         | 'DIP'          | ''          | ''            | '20151215'
 '220UF'  | '6.3V'  | '20%'       | 'SMLF'      | 'ALUM'     | 'CC72201MZ27'(!)             = ''              | ''                 | 'CC72201MZ27'                |'EC56_197_233S'| '220UF'  | '6.3V'        | '20%'       | 'DISCRETE' | 'CAP OSCON SMD 220U 6.3V(20%,5*5.8)SAY'                | 'SMT'          | ''          | ''            | '20160122'
 '220UF'  | '6.3V'  | '20%'       | 'SMLF'      | 'EMPTY'    | 'CC72201MZ27'(!)             = ''              | ''                 | 'CC72201MZ27'                |'EC56_197_233S'| '220UF'  | '6.3V'        | '20%'       | 'IO'       | 'CAP OSCON SMD 220U 6.3V(20%,5*5.8)SAY'                | 'SMT'          | ''          | ''            | '20160122'
 '100UF'  | '16V'   | '20%'       | 'SMLF'      | 'POSCAP'   | 'CH7103MI803'(!)             = 'End of Design' | 'Comp-Approve'     | 'CH7103MI803'                |'TAJ_7343-20'| '100UF'  | '16V'         | '20%'       | 'DISCRETE' | 'CAP CHIP 100UF 16V(20%,POSCAP,7343)KEM'               | 'SMT'          | ''          | ''            | '20160523'
 '100UF'  | '16V'   | '20%'       | 'SMLF'      | 'EMPTY'    | 'CH7103MI803'(!)             = 'End of Design' | 'Comp-Approve'     | 'CH7103MI803'                |'TAJ_7343-20'| '100UF'  | '16V'         | '20%'       | 'IO'       | 'CAP CHIP 100UF 16V(20%,POSCAP,7343)KEM'               | 'SMT'          | ''          | ''            | '20160523'
 '220UF'  | '16V'   | '20%'       | 'SMLF'      | 'ALUM'     | 'CC72203MZ35'(!)             = 'End of Design' | 'Comp-Approve'     | 'CC72203MZ35'                |'EC87_248_303S'| '220UF'  | '16V'         | '20%'       | 'DISCRETE' | 'CAP SMD 220U 16V(+-20%.105C.6.3*7.7)'                 | 'SMT'          | ''          | ''            | '20160526'
 '220UF'  | '16V'   | '20%'       | 'SMLF'      | 'EMPTY'    | 'CC72203MZ35'(!)             = 'End of Design' | 'Comp-Approve'     | 'CC72203MZ35'                |'EC87_248_303S'| '220UF'  | '16V'         | '20%'       | 'IO'       | 'CAP SMD 220U 16V(+-20%.105C.6.3*7.7)'                 | 'SMT'          | ''          | ''            | '20160526'
 '820UF'  | '16V'   | '20%'       | 'RDLF'      | 'OSCON'    | 'CC78203MD04'(!)             = ''              | ''                 | 'CC78203MD04'                |'EC197_394_473'| '820UF'  | '16V'         | '20%'       | 'DISCRETE' | 'CAP OSCON DIP 820U 16V(20%,ESR10,10*12)'              | 'DIP'          | ''          | ''            | '20160725'
 '820UF'  | '16V'   | '20%'       | 'RDLF'      | 'EMPTY'    | 'CC78203MD04'(!)             = ''              | ''                 | 'CC78203MD04'                |'EC197_394_473'| '820UF'  | '16V'         | '20%'       | 'IO'       | 'CAP OSCON DIP 820U 16V(20%,ESR10,10*12)'              | 'DIP'          | ''          | ''            | '20160725'
 '33UF'   | '16V'   | '20%'       | 'SMLF'      | 'POSCAP'   | 'CH6333MI606'(!)             = 'End of Design' | 'Comp-Approve'     | 'CH6333MI606'                |'TAJ_B2XA'| '33UF'   | '16V'         | '20%'       | 'DISCRETE' | 'CAP CHIP 33U 16V(20%,POSCAP,ESR70,3528)'              | 'SMT'          | ''          | ''            | '20160923'
 '33UF'   | '16V'   | '20%'       | 'SMLF'      | 'EMPTY'    | 'CH6333MI606'(!)             = 'End of Design' | 'Comp-Approve'     | 'CH6333MI606'                |'TAJ_B2XA'| '33UF'   | '16V'         | '20%'       | 'IO'       | 'CAP CHIP 33U 16V(20%,POSCAP,ESR70,3528)'              | 'SMT'          | ''          | ''            | '20160923'
 '330UF'  | '6.3V'  | '20%'       | 'SMLF'      | 'TANT'     | 'CH7331M8869'(!)             = 'End of Design' | 'Comp-Approve'     | 'CH7331M8869'                |'TAJ_DXB'| '330UF'  | '6.3V'        | '20%'       | 'DISCRETE' | 'CAP CHIP 330U 6.3V(20%,ESR15,7343,H2.8)'              | 'SMT'          | ''          | ''            | '20161020'
 '330UF'  | '6.3V'  | '20%'       | 'SMLF'      | 'EMPTY'    | 'CH7331M8869'(!)             = 'End of Design' | 'Comp-Approve'     | 'CH7331M8869'                |'TAJ_DXB'| '330UF'  | '6.3V'        | '20%'       | 'IO'       | 'CAP CHIP 330U 6.3V(20%,ESR15,7343,H2.8)'              | 'SMT'          | ''          | ''            | '20161020'
 '3900UF' | '16V'   | '20%'       | 'THLF'      | ''         | 'CC83903MD00'(!)             = ''              | ''                 | 'CC83903MD00'                |'EC197_493_1378'| '3900UF' | '16V'         | '20%'       | 'DISCRETE' | 'CAP ELEC DIP 3900U 16V(20%,105C,12.5*35)'             | 'DIP'          | ''          | ''            | '20161020'
 '3900UF' | '16V'   | '20%'       | 'THLF'      | 'EMPTY'    | 'CC83903MD00'(!)             = ''              | ''                 | 'CC83903MD00'                |'EC197_493_1378'| '3900UF' | '16V'         | '20%'       | 'IO'       | 'CAP ELEC DIP 3900U 16V(20%,105C,12.5*35)'             | 'DIP'          | ''          | ''            | '20161020'
 '3900UF' | '16V'   | '20%'       | 'THLF'      | ''         | 'CC83903MD01'(!)             = ''              | ''                 | 'CC83903MD01'                |'EC197_493_1240'| '3900UF' | '16V'         | '20%'       | 'DISCRETE' | 'CAP ELEC DIP 3900U 16V(20%,12.5*31.5)'                | 'DIP'          | ''          | ''            | '20161021'
 '3900UF' | '16V'   | '20%'       | 'THLF'      | 'EMPTY'    | 'CC83903MD01'(!)             = ''              | ''                 | 'CC83903MD01'                |'EC197_493_1240'| '3900UF' | '16V'         | '20%'       | 'IO'       | 'CAP ELEC DIP 3900U 16V(20%,12.5*31.5)'                | 'DIP'          | ''          | ''            | '20161021'
 '4700UF' | '16V'   | '20%'       | 'THLF'      | ''         | 'CC84703MD00'(!)             = ''              | ''                 | 'CC84703MD00'                |'EC197_493_1398'| '4700UF' | '16V'         | '20%'       | 'DISCRETE' | 'CAP ELEC DIP 4700U 16V(20%,12.5*35.5)'                | 'DIP'          | ''          | ''            | '20161028'
 '4700UF' | '16V'   | '20%'       | 'THLF'      | 'EMPTY'    | 'CC84703MD00'(!)             = ''              | ''                 | 'CC84703MD00'                |'EC197_493_1398'| '4700UF' | '16V'         | '20%'       | 'IO'       | 'CAP ELEC DIP 4700U 16V(20%,12.5*35.5)'                | 'DIP'          | ''          | ''            | '20161028'
 '1000UF' | '16V'   | '20%'       | 'THLF'      | 'OSCON'    | 'CC81003MD10'(!)             = ''              | ''                 | 'CC81003MD10'                |'EC5_10-5_13'| '1000UF' | '16V'         | '20%'       | 'DISCRETE' | 'CAP OSCON DIP 1000U 16V(20%,10*11.5)'                 | 'DIP'          | ''          | ''            | '20170405'
 '1000UF' | '16V'   | '20%'       | 'THLF'      | 'EMPTY'    | 'CC81003MD10'(!)             = ''              | ''                 | 'CC81003MD10'                |'EC5_10-5_13'| '1000UF' | '16V'         | '20%'       | 'IO'       | 'CAP OSCON DIP 1000U 16V(20%,10*11.5)'                 | 'DIP'          | ''          | ''            | '20170405'
 '220UF'  | '6.3V'  | '20%'       | 'SMLF'      | 'ALUM'     | 'CC72201MZ28'(!)             = ''              | ''                 | 'CC72201MZ28'                |'EC56_197_229SXA'| '220UF'  | '6.3V'        | '20%'       | 'DISCRETE' | 'CAP OSCON SMD 220U 6.3V(20%,5*5.8)NPN'                | 'SMT'          | ''          | ''            | '20170503'
 '220UF'  | '6.3V'  | '20%'       | 'SMLF'      | 'EMPTY'    | 'CC72201MZ28'(!)             = ''              | ''                 | 'CC72201MZ28'                |'EC56_197_229SXA'| '220UF'  | '6.3V'        | '20%'       | 'IO'       | 'CAP OSCON SMD 220U 6.3V(20%,5*5.8)NPN'                | 'SMT'          | ''          | ''            | '20170503'
 '390UF'  | '2.5V'  | '20%'       | 'SMLF'      | 'ALUM'     | 'CC7390JMZ13'(!)             = ''              | ''                 | 'CC7390JMZ13'                |'EC56_197_229SXA'| '390UF'  | '2.5V'        | '20%'       | 'DISCRETE' | 'CAP OSCON SMD 390U 2.5V(20%,5*5.8)NPN'                | 'SMT'          | ''          | ''            | '20170503'
 '390UF'  | '2.5V'  | '20%'       | 'SMLF'      | 'EMPTY'    | 'CC7390JMZ13'(!)             = ''              | ''                 | 'CC7390JMZ13'                |'EC56_197_229SXA'| '390UF'  | '2.5V'        | '20%'       | 'IO'       | 'CAP OSCON SMD 390U 2.5V(20%,5*5.8)NPN'                | 'SMT'          | ''          | ''            | '20170503'
 '180UF'  | '16V'   | '20%'       | 'SMLF'      | 'ALUM'     | 'CC71803MZ07'(!)             = ''              | ''                 | 'CC71803MZ07'                |'EC83_248_233S'| '180UF'  | '16V'         | '20%'       | 'DISCRETE' | 'CAP OSCON SMD 180U 16V(20%,6.3*5.9)SAY'               | 'SMT'          | ''          | ''            | '20170505'
 '180UF'  | '16V'   | '20%'       | 'SMLF'      | 'EMPTY'    | 'CC71803MZ07'(!)             = ''              | ''                 | 'CC71803MZ07'                |'EC83_248_233S'| '180UF'  | '16V'         | '20%'       | 'IO'       | 'CAP OSCON SMD 180U 16V(20%,6.3*5.9)SAY'               | 'SMT'          | ''          | ''            | '20170505'
 '180UF'  | '16V'   | '20%'       | 'SMLF'      | 'ALUM'     | 'CC71803MZ08'(!)             = ''              | ''                 | 'CC71803MZ08'                |'EC75_248_229S'| '180UF'  | '16V'         | '20%'       | 'DISCRETE' | 'CAP OSCON SMD 180U 16V(20%,6.3*5.8)NPN'               | 'SMT'          | ''          | ''            | '20170505'
 '180UF'  | '16V'   | '20%'       | 'SMLF'      | 'EMPTY'    | 'CC71803MZ08'(!)             = ''              | ''                 | 'CC71803MZ08'                |'EC75_248_229S'| '180UF'  | '16V'         | '20%'       | 'IO'       | 'CAP OSCON SMD 180U 16V(20%,6.3*5.8)NPN'               | 'SMT'          | ''          | ''            | '20170505'
 '100UF'  | '16V'   | '20%'       | 'THLF'      | 'OSCON'    | 'CC71003MD19'(!)             = 'End of Design' | 'Comp-Approve'     | 'CC71003MD19'                |'EC98_248_237'| '100UF'  | '16V'         | '20%'       | 'DISCRETE' | 'CAP OSCON DIP 100U 16V(20%,6.3*6)SAY'                 | 'DIP'          | ''          | ''            | '20170505'
 '100UF'  | '16V'   | '20%'       | 'THLF'      | 'EMPTY'    | 'CC71003MD19'(!)             = 'End of Design' | 'Comp-Approve'     | 'CC71003MD19'                |'EC98_248_237'| '100UF'  | '16V'         | '20%'       | 'IO'       | 'CAP OSCON DIP 100U 16V(20%,6.3*6)SAY'                 | 'DIP'          | ''          | ''            | '20170505'
 '560UF'  | '2.5V'  | '20%'       | 'THLF'      | 'OSCON'    | 'CC7560JMD15'(!)             = ''              | ''                 | 'CC7560JMD15'                |'EC2_5-5_9'| '560UF'  | '2.5V'        | '20%'       | 'DISCRETE' | 'CAP OSCON DIP 560U 2.5V(20%,105C,5*8)NPN'             | 'DIP'          | ''          | ''            | '20170519'
 '560UF'  | '2.5V'  | '20%'       | 'THLF'      | 'EMPTY'    | 'CC7560JMD15'(!)             = ''              | ''                 | 'CC7560JMD15'                |'EC2_5-5_9'| '560UF'  | '2.5V'        | '20%'       | 'IO'       | 'CAP OSCON DIP 560U 2.5V(20%,105C,5*8)NPN'             | 'DIP'          | ''          | ''            | '20170519'
 '560UF'  | '2.5V'  | '20%'       | 'THLF'      | 'OSCON'    | 'SP_CC7560JMD15'(!)          = ''              | ''                 | 'CC7560JMD15'                |'G_EC2_5-5_9'| '560UF'  | '2.5V'        | '20%'       | 'DISCRETE' | 'CAP OSCON DIP 560U 2.5V(20%,105C,5*8)NPN_FOR SEL'     | 'DIP'          | ''          | ''            | '20170519'
 '560UF'  | '2.5V'  | '20%'       | 'THLF'      | 'EMPTY'    | 'SP_CC7560JMD15'(!)          = ''              | ''                 | 'CC7560JMD15'                |'G_EC2_5-5_9'| '560UF'  | '2.5V'        | '20%'       | 'IO'       | 'CAP OSCON DIP 560U 2.5V(20%,105C,5*8)NPN_FOR SEL'     | 'DIP'          | ''          | ''            | '20170519'
 '220UF'  | '4V'    | '20%'       | 'SMLF'      | 'TANT'     | 'CH122KM8800'(!)             = ''              | ''                 | 'CH122KM8800'                |'TAJ_SX'| '220UF'  | '4V'          | '20%'       | 'DISCRETE' | 'CAP CHIP 220U 4V(+-20%,SPCAP,7343)'                   | 'SMT'          | ''          | ''            | '20170602'
 '220UF'  | '4V'    | '20%'       | 'SMLF'      | 'EMPTY'    | 'CH122KM8800'(!)             = ''              | ''                 | 'CH122KM8800'                |'TAJ_SX'| '220UF'  | '4V'          | '20%'       | 'IO'       | 'CAP CHIP 220U 4V(+-20%,SPCAP,7343)'                   | 'SMT'          | ''          | ''            | '20170602'
 '270UF'  | '16V'   | '20%'       | 'THLF'      | 'OSCON'    | 'CC72703MD31'(!)             = ''              | ''                 | 'CC72703MD31'                |'EC98_248_315XA'| '270UF'  | '16V'         | '20%'       | 'DISCRETE' | 'CAP OSCON DIP 270U 16V(20%,6.3*8)NPN'                 | 'DIP'          | ''          | ''            | '20170628'
 '270UF'  | '16V'   | '20%'       | 'THLF'      | 'EMPTY'    | 'CC72703MD31'(!)             = ''              | ''                 | 'CC72703MD31'                |'EC98_248_315XA'| '270UF'  | '16V'         | '20%'       | 'IO'       | 'CAP OSCON DIP 270U 16V(20%,6.3*8)NPN'                 | 'DIP'          | ''          | ''            | '20170628'
 '270UF'  | '16V'   | '20%'       | 'THLF'      | 'OSCON'    | 'SP_CC72703MD31'(!)          = ''              | ''                 | 'CC72703MD31'                |'G_EC98_248_315XA'| '270UF'  | '16V'         | '20%'       | 'DISCRETE' | 'CAP OSCON DIP 270U 16V(20%,6.3*8)NPN_FOR SEL'         | 'DIP'          | ''          | ''            | '20170628'
 '270UF'  | '16V'   | '20%'       | 'THLF'      | 'EMPTY'    | 'SP_CC72703MD31'(!)          = ''              | ''                 | 'CC72703MD31'                |'G_EC98_248_315XA'| '270UF'  | '16V'         | '20%'       | 'IO'       | 'CAP OSCON DIP 270U 16V(20%,6.3*8)NPN_FOR SEL'         | 'DIP'          | ''          | ''            | '20170628'
 '15UF'   | '25V'   | '20%'       | 'SMLF'      | 'ALUM'     | 'CC61504MZ05'(!)             = ''              | ''                 | 'CC61504MZ05'                |'EC75_248_174S'| '15UF'   | '25V'         | '20%'       | 'DISCRETE' | 'CAP ELECSMD15U 25V(20%,105C,6.3*4.4)NPN'              | 'SMT'          | ''          | ''            | '20170927'
 '15UF'   | '25V'   | '20%'       | 'SMLF'      | 'EMPTY'    | 'CC61504MZ05'(!)             = ''              | ''                 | 'CC61504MZ05'                |'EC75_248_174S'| '15UF'   | '25V'         | '20%'       | 'IO'       | 'CAP ELECSMD15U 25V(20%,105C,6.3*4.4)NPN'              | 'SMT'          | ''          | ''            | '20170927'
 '220UF'  | '2V'    | '20%'       | 'SMLF'      | 'POSCAP'   | 'CH722RM8811'(!)             = ''              | ''                 | 'CH722RM8811'                |'TAJ_SX_H40'| '220UF'  | '2V'          | '20%'       | 'DISCRETE' | 'CAP CHIP 220U 2V(20%ESR4.5,SPCAP,7343)H1'             | 'SMT'          | ''          | ''            | '20171017'
 '220UF'  | '2V'    | '20%'       | 'SMLF'      | 'EMPTY'    | 'CH722RM8811'(!)             = ''              | ''                 | 'CH722RM8811'                |'TAJ_SX_H40'| '220UF'  | '2V'          | '20%'       | 'IO'       | 'CAP CHIP 220U 2V(20%ESR4.5,SPCAP,7343)H1'             | 'SMT'          | ''          | ''            | '20171017'
 '470UF'  | '2V'    | '20%'       | 'SMLF'      | 'TANT'     | 'CH747RM8803'(!)             = ''              | ''                 | 'CH747RM8803'                |'TAJ_SX'| '470UF'  | '2V'          | '20%'       | 'DISCRETE' | 'CAP CHIP 470U 2V(20%.ESR4.5.7343.H1.8)'               | 'SMT'          | ''          | ''            | '20171024'
 '470UF'  | '2V'    | '20%'       | 'SMLF'      | 'EMPTY'    | 'CH747RM8803'(!)             = ''              | ''                 | 'CH747RM8803'                |'TAJ_SX'| '470UF'  | '2V'          | '20%'       | 'IO'       | 'CAP CHIP 470U 2V(20%.ESR4.5.7343.H1.8)'               | 'SMT'          | ''          | ''            | '20171024'
 '220UF'  | '6.3V'  | '20%'       | 'SMLF'      | 'TANT'     | 'CH7221M8600'(!)             = 'End of Design' | 'Comp-Release Qty' | 'CH7221M8600'                |'TAJ_B2XA'| '220UF'  | '6.3V'        | '20%'       | 'DISCRETE' | 'CAP CHIP 220U 6.3V(+-20%,ESR35,3528)H1.9'             | 'SMT'          | ''          | ''            | '20171129'
 '220UF'  | '6.3V'  | '20%'       | 'SMLF'      | 'EMPTY'    | 'CH7221M8600'(!)             = 'End of Design' | 'Comp-Release Qty' | 'CH7221M8600'                |'TAJ_B2XA'| '220UF'  | '6.3V'        | '20%'       | 'IO'       | 'CAP CHIP 220U 6.3V(+-20%,ESR35,3528)H1.9'             | 'SMT'          | ''          | ''            | '20171129'
 '330UF'  | '2V'    | '35%'       | 'SMLF'      | 'SPCAP'    | 'CH733RY8807'(!)             = ''              | ''                 | 'CH733RY8807'                |'TAJ_DXC'| '330U'   | '2V'          | '35%'       | 'DISCRETE' | 'CAP CHIP 330U 2V(+10-35%,SPCAP,7343)MAT'              | 'SMT'          | ''          | ''            | '20171206'
 '330UF'  | '2V'    | '35%'       | 'SMLF'      | 'EMPTY'    | 'CH733RY8807'(!)             = ''              | ''                 | 'CH733RY8807'                |'TAJ_DXC'| '330U'   | '2V'          | '35%'       | 'IO'       | 'CAP CHIP 330U 2V(+10-35%,SPCAP,7343)MAT'              | 'SMT'          | ''          | ''            | '20171206'
 '560UF'  | '2.5V'  | '20%'       | 'SMLF'      | 'OSCON'    | 'CC7560JMZ15'(!)             = ''              | ''                 | 'CC7560JMZ15'                |'EC83_248_232S'| '560UF'  | '2.5V'        | '20%'       | 'DISCRETE' | 'CAP OSCON 560U 2.5V(20%.105C.6.3*5.7)SMD'             | 'SMT'          | ''          | ''            | '20180201'
 '560UF'  | '2.5V'  | '20%'       | 'SMLF'      | 'EMPTY'    | 'CC7560JMZ15'(!)             = ''              | ''                 | 'CC7560JMZ15'                |'EC83_248_232S'| '560UF'  | '2.5V'        | '20%'       | 'IO'       | 'CAP OSCON 560U 2.5V(20%.105C.6.3*5.7)SMD'             | 'SMT'          | ''          | ''            | '20180201'
 '15UF'   | '25V'   | '20%'       | 'SMLF'      | 'OSCON'    | 'CC61504MZ07'(!)             = ''              | ''                 | 'CC61504MZ07'                |'EC83_248_166S'| '15U'    | '25V'         | '20%'       | 'DISCRETE' | 'CAP OSCON SMD 15U 25V(20%,6.3*4.4)SAY'                | 'SMT'          | ''          | ''            | '20180323'
 '15UF'   | '25V'   | '20%'       | 'SMLF'      | 'EMPTY'    | 'CC61504MZ07'(!)             = ''              | ''                 | 'CC61504MZ07'                |'EC83_248_166S'| '15U'    | '25V'         | '20%'       | 'IO'       | 'CAP OSCON SMD 15U 25V(20%,6.3*4.4)SAY'                | 'SMT'          | ''          | ''            | '20180323'
 '560UF'  | '16V'   | '20%'       | 'SMLF'      | 'OSCON'    | 'CC75603MZ00'(!)             = 'End of Design' | 'Comp-Approve'     | 'CC75603MZ00'                |'EC122_315_394S'| '560UF'  | '16V'         | '20%'       | 'DISCRETE' | 'CAP OSCON SMD 560U 16V(20%,ESR18,8*10)'               | 'SMT'          | ''          | ''            | '20170810'
 '560UF'  | '16V'   | '20%'       | 'SMLF'      | 'EMPTY'    | 'CC75603MZ00'(!)             = 'End of Design' | 'Comp-Approve'     | 'CC75603MZ00'                |'EC122_315_394S'| '560UF'  | '16V'         | '20%'       | 'IO'       | 'CAP OSCON SMD 560U 16V(20%,ESR18,8*10)'               | 'SMT'          | ''          | ''            | '20170810'
 '220UF'  | '6.3V'  | '20%'       | 'SMLF'      | 'OSCON'    | 'CC72201MZ03'(!)             = ''              | ''                 | 'CC72201MZ03'                |'EC83_248_166S'| '220U'   | '6.3V'        | '20%'       | 'DISCRETE' | 'CAP ELEC SMD 220U 6.3V(+-20%.6.3*4.2)'                | 'SMT'          | ''          | ''            | '20180515'
 '220UF'  | '6.3V'  | '20%'       | 'SMLF'      | 'EMPTY'    | 'CC72201MZ03'(!)             = ''              | ''                 | 'CC72201MZ03'                |'EC83_248_166S'| '220U'   | '6.3V'        | '20%'       | 'IO'       | 'CAP ELEC SMD 220U 6.3V(+-20%.6.3*4.2)'                | 'SMT'          | ''          | ''            | '20180515'
 '150UF'  | '6.3V'  | '20%'       | 'SMLF'      | ''         | 'CC71501MZ07'(!)             = 'End of Design' | 'Comp-Approve'     | 'CC71501MZ07'                |'EC56_197_158S'| '150UF'  | '6.3V'        | '20%'       | 'DISCRETE' | 'CAP ELEC SMD 150U 6.3V(20%,ESR20,5*3.9)'              | 'SMT'          | ''          | ''            | '20180515'
 '150UF'  | '6.3V'  | '20%'       | 'SMLF'      | 'EMPTY'    | 'CC71501MZ07'(!)             = 'End of Design' | 'Comp-Approve'     | 'CC71501MZ07'                |'EC56_197_158S'| '150UF'  | '6.3V'        | '20%'       | 'IO'       | 'CAP ELEC SMD 150U 6.3V(20%,ESR20,5*3.9)'              | 'SMT'          | ''          | ''            | '20180515'
 '470UF'  | '2.5V'  | '20%'       | 'SMLF'      | 'OSCON'    | 'CC7470JMD00'(!)             = ''              | ''                 | 'CC7470JMD00'                |'EC79_213_374'| '470UF'  | '2.5V'        | '20%'       | 'DISCRETE' | 'CAP OSCON DIP 470U 2.5V(20%,5.4*8)'                   | 'DIP'          | ''          | ''            | '20180605'
 '470UF'  | '2.5V'  | '20%'       | 'SMLF'      | 'EMPTY'    | 'CC7470JMD00'(!)             = ''              | ''                 | 'CC7470JMD00'                |'EC79_213_374'| '470UF'  | '2.5V'        | '20%'       | 'IO'       | 'CAP OSCON DIP 470U 2.5V(20%,5.4*8)'                   | 'DIP'          | ''          | ''            | '20180605'
 '470UF'  | '16V'   | '20%'       | 'THLF'      | ''         | 'CC74703MD18'(!)             = 'End of Design' | 'Comp-Approve'     | 'CC74703MD18'                |'EC138_315_453'| '470UF'  | '16V'         | '20%'       | 'DISCRETE' | 'CAP ELEC DIP 470U 16V(+-20%,105C,8*11.5)'             | 'DIP'          | ''          | ''            | '20180605'
 '470UF'  | '16V'   | '20%'       | 'THLF'      | 'EMPTY'    | 'CC74703MD18'(!)             = 'End of Design' | 'Comp-Approve'     | 'CC74703MD18'                |'EC138_315_453'| '470UF'  | '16V'         | '20%'       | 'IO'       | 'CAP ELEC DIP 470U 16V(+-20%,105C,8*11.5)'             | 'DIP'          | ''          | ''            | '20180605'
 '47UF'   | '20V'   | '20%'       | 'SMLF'      | 'ALUM'     | 'CC6470HMZ00'(!)             = 'End of Design' | 'Comp-Approve'     | 'CC6470HMZ00'                |'EC75_248_174S'| '47UF'   | '20V'         | '20%'       | 'DISCRETE' | 'CAP ELEC SMD 47U 20V(20%,105C,6.3*4.4)'               | 'SMT'          | ''          | ''            | '20180926'
 '47UF'   | '20V'   | '20%'       | 'SMLF'      | 'EMPTY'    | 'CC6470HMZ00'(!)             = 'End of Design' | 'Comp-Approve'     | 'CC6470HMZ00'                |'EC75_248_174S'| '47UF'   | '20V'         | '20%'       | 'IO'       | 'CAP ELEC SMD 47U 20V(20%,105C,6.3*4.4)'               | 'SMT'          | ''          | ''            | '20180926'
 '560U'   | '100V'  | '20%'       | 'THLF'      | 'ALUM'     | 'CC75608MD00'(!)             = ''              | 'End of Life'      | 'CC75608MD00'                |'EC296_709_985_EOL'| '560U'   | '100V'        | '20%'       | 'DISCRETE' | 'CAP ELEC DIP 560U 100V(20%,18*25)'                    | 'DIP'          | ''          | ''            | '20180928'
 '560U'   | '100V'  | '20%'       | 'THLF'      | 'EMPTY'    | 'CC75608MD00'(!)             = ''              | 'End of Life'      | 'CC75608MD00'                |'EC296_709_985_EOL'| '560U'   | '100V'        | '20%'       | 'IO'       | 'CAP ELEC DIP 560U 100V(20%,18*25)'                    | 'DIP'          | ''          | ''            | '20180928'
 '470U'   | '25V'   | '20%'       | 'SMLF'      | ''         | 'CC74704MZ26'(!)             = ''              | ''                 | 'CC74704MZ26'                |'EC181_394_402SXA'| '470U'   | '25V'         | '20%'       | 'DISCRETE' | 'CAP ELEC 470U25V(20%105C,10*10.2 ESR)'                | 'SMT'          | ''          | ''            | '20180928'
 '470U'   | '25V'   | '20%'       | 'SMLF'      | 'EMPTY'    | 'CC74704MZ26'(!)             = ''              | ''                 | 'CC74704MZ26'                |'EC181_394_402SXA'| '470U'   | '25V'         | '20%'       | 'IO'       | 'CAP ELEC 470U25V(20%105C,10*10.2 ESR)'                | 'SMT'          | ''          | ''            | '20180928'
 '10F'    | '3V'    | '20%'       | 'SMLF'      | ''         | 'CCC100KMD00'(!)             = ''              | ''                 | 'CCC100KMD00'                |'EC197_394_1182'| '10F'    | '3V'          | '20%'       | 'DISCRETE' | 'CAP ELEC DIP 10F 3V (20%,10*30)SUPER'                 | 'DIP'          | ''          | ''            | '20181005'
 '10F'    | '3V'    | '20%'       | 'SMLF'      | 'EMPTY'    | 'CCC100KMD00'(!)             = ''              | ''                 | 'CCC100KMD00'                |'EC197_394_1182'| '10F'    | '3V'          | '20%'       | 'IO'       | 'CAP ELEC DIP 10F 3V (20%,10*30)SUPER'                 | 'DIP'          | ''          | ''            | '20181005'
 '25F'    | '3V'    | '30%'       | 'THLF'      | '    '     | 'CCC250KZD00'(!)             = 'Non-Preferred' | 'End of Life'      | 'CCC250KZD00'                |'EC296_650_1119_EOL'| '25F'    | '3V'          | '30%'       | 'DISCRETE' | 'CAP ELEC DIP 25F 3V(-10/+30%,16*25)SUPER'             | 'DIP'          | ''          | ''            | '20181012'
 '25F'    | '3V'    | '30%'       | 'THLF'      | 'EMPTY'    | 'CCC250KZD00'(!)             = 'Non-Preferred' | 'End of Life'      | 'CCC250KZD00'                |'EC296_650_1119_EOL'| '25F'    | '3V'          | '30%'       | 'IO'       | 'CAP ELEC DIP 25F 3V(-10/+30%,16*25)SUPER'             | 'DIP'          | ''          | ''            | '20181012'
 '6800U'  | '16V'   | '20%'       | 'SMLF'      | ''         | 'CC86803MD00'(!)             = ''              | ''                 | 'CC86803MD00'                |'EC296_630_1241'| '6800U'  | '16V'         | '20%'       | 'DISCRETE' | 'CAP ELEC DIP 6800U 16V(20%,16*31.5)'                  | 'DIP'          | ''          | ''            | '20181015'
 '6800U'  | '16V'   | '20%'       | 'SMLF'      | 'EMPTY'    | 'CC86803MD00'(!)             = ''              | ''                 | 'CC86803MD00'                |'EC296_630_1241'| '6800U'  | '16V'         | '20%'       | 'IO'       | 'CAP ELEC DIP 6800U 16V(20%,16*31.5)'                  | 'DIP'          | ''          | ''            | '20181015'
 '3900U'  | '16V'   | '20%'       | 'SMLF'      | ''         | 'CC83903MD02'(!)             = ''              | ''                 | 'CC83903MD02'                |'EC197_493_1182'| '3900U'  | '16V'         | '20%'       | 'DISCRETE' | 'CAP ELEC DIP 3900U 16V(20%,12.5*30)'                  | 'DIP'          | ''          | ''            | '20181015'
 '3900U'  | '16V'   | '20%'       | 'SMLF'      | 'EMPTY'    | 'CC83903MD02'(!)             = ''              | ''                 | 'CC83903MD02'                |'EC197_493_1182'| '3900U'  | '16V'         | '20%'       | 'IO'       | 'CAP ELEC DIP 3900U 16V(20%,12.5*30)'                  | 'DIP'          | ''          | ''            | '20181015'
 '150UF'  | '16V'   | '20%'       | 'SMLF'      | 'OSCON'    | 'CC71503MZ00'(!)             = ''              | ''                 | 'CC71503MZ00'                |'EC83_248_232S'| '150UF'  | '16V'         | '20%'       | 'DISCRETE' | 'CAP OSCON SMD 150U 16V(20%.105C.6.3*5.9)'             | 'SMT'          | ''          | ''            | '20181018'
 '150UF'  | '16V'   | '20%'       | 'SMLF'      | 'EMPTY'    | 'CC71503MZ00'(!)             = ''              | ''                 | 'CC71503MZ00'                |'EC83_248_232S'| '150UF'  | '16V'         | '20%'       | 'IO'       | 'CAP OSCON SMD 150U 16V(20%.105C.6.3*5.9)'             | 'SMT'          | ''          | ''            | '20181018'
 '10F'    | '3V'    | '30%'       | 'THLF'      | ''         | 'CCC100KTD00'(!)             = ''              | ''                 | 'CCC100KTD00'                |'EC197_414_1241'| '10F'    | '3V'          | '30%'       | 'DISCRETE' | 'CAP ELEC DIP 10F 3V(-10/+30%,10*30)SUPER'             | 'DIP'          | ''          | ''            | '20181023'
 '10F'    | '3V'    | '30%'       | 'THLF'      | 'EMPTY'    | 'CCC100KTD00'(!)             = ''              | ''                 | 'CCC100KTD00'                |'EC197_414_1241'| '10F'    | '3V'          | '30%'       | 'IO'       | 'CAP ELEC DIP 10F 3V(-10/+30%,10*30)SUPER'             | 'DIP'          | ''          | ''            | '20181023'
 '390UF'  | '20V'   | '20%'       | 'SMLF'      | 'OSCON'    | 'CC73903MZ01'(!)             = ''              | ''                 | 'CC73903MZ01'                |'EC122_315_394S'| '390UF'  | '20V'         | '20%'       | 'DISCRETE' | 'CAP OSCON SMD 390U 20V(20%,8*10)NPN'                  | 'SMT'          | ''          | ''            | '20181026'
 '390UF'  | '20V'   | '20%'       | 'SMLF'      | 'EMPTY'    | 'CC73903MZ01'(!)             = ''              | ''                 | 'CC73903MZ01'                |'EC122_315_394S'| '390UF'  | '20V'         | '20%'       | 'IO'       | 'CAP OSCON SMD 390U 20V(20%,8*10)NPN'                  | 'SMT'          | ''          | ''            | '20181026'
 '390UF'  | '20V'   | '20%'       | 'SMLF'      | 'OSCON'    | 'CC73903MZ00'(!)             = ''              | ''                 | 'CC73903MZ00'                |'EC126_315_469SXA'| '390UF'  | '20V'         | '20%'       | 'DISCRETE' | 'CAP OSCON SMD 390U 20V(20%,8*11.9)SAY'                | 'SMT'          | ''          | ''            | '20181026'
 '390UF'  | '20V'   | '20%'       | 'SMLF'      | 'EMPTY'    | 'CC73903MZ00'(!)             = ''              | ''                 | 'CC73903MZ00'                |'EC126_315_469SXA'| '390UF'  | '20V'         | '20%'       | 'IO'       | 'CAP OSCON SMD 390U 20V(20%,8*11.9)SAY'                | 'SMT'          | ''          | ''            | '20181026'
 '560UF'  | '20V'   | '20%'       | 'SMLF'      | 'OSCON'    | 'CC75603MZ05'(!)             = ''              | ''                 | 'CC75603MZ05'                |'EC181_394_496SXA'| '560UF'  | '20V'         | '20%'       | 'DISCRETE' | 'CAP OSCON SMD 560U 20V(20%,10*12.6)SAY'               | 'SMT'          | ''          | ''            | '20181026'
 '560UF'  | '20V'   | '20%'       | 'SMLF'      | 'EMPTY'    | 'CC75603MZ05'(!)             = ''              | ''                 | 'CC75603MZ05'                |'EC181_394_496SXA'| '560UF'  | '20V'         | '20%'       | 'IO'       | 'CAP OSCON SMD 560U 20V(20%,10*12.6)SAY'               | 'SMT'          | ''          | ''            | '20181026'
 '560UF'  | '20V'   | '20%'       | 'SMLF'      | 'OSCON'    | 'CC75603MZ06'(!)             = ''              | ''                 | 'CC75603MZ06'                |'EC178_394_394SXA_H414'| '560UF'  | '20V'         | '20%'       | 'DISCRETE' | 'CAP OSCON SMD 560U 20V(20%,10*10)NPN'                 | 'SMT'          | ''          | ''            | '20181026'
 '560UF'  | '20V'   | '20%'       | 'SMLF'      | 'EMPTY'    | 'CC75603MZ06'(!)             = ''              | ''                 | 'CC75603MZ06'                |'EC178_394_394SXA_H414'| '560UF'  | '20V'         | '20%'       | 'IO'       | 'CAP OSCON SMD 560U 20V(20%,10*10)NPN'                 | 'SMT'          | ''          | ''            | '20181026'
 '2200U'  | '16V'   | '20%'       | 'THLF'      | '     '    | 'CC82203MD06'(!)             = ''              | ''                 | 'CC82203MD06'                |'EC197_394_1182'| '2200U'  | '16V'         | '20%'       | 'DISCRETE' | 'CAP ELEC DIP 2200U 16V(20%,10*30)'                    | 'DIP'          | ''          | ''            | '20181108'
 '2200U'  | '16V'   | '20%'       | 'THLF'      | 'EMPTY'    | 'CC82203MD06'(!)             = ''              | ''                 | 'CC82203MD06'                |'EC197_394_1182'| '2200U'  | '16V'         | '20%'       | 'IO'       | 'CAP ELEC DIP 2200U 16V(20%,10*30)'                    | 'DIP'          | ''          | ''            | '20181108'
 '1000U'  | '16V'   | '20%'       | 'SMLF'      | 'OSCON'    | 'CC81003MZ01'(!)             = 'End of Design' | 'Comp-Approve'     | 'CC81003MZ01'                |'EC178_394_394SXA_H414'| '1000U'  | '16V'         | '20%'       | 'DISCRETE' | 'CAP OSCON SMD 1000U 16V(20%,ESR18,10*10)'             | 'SMT'          | ''          | ''            | '20181119'
 '1000U'  | '16V'   | '20%'       | 'SMLF'      | 'EMPTY'    | 'CC81003MZ01'(!)             = 'End of Design' | 'Comp-Approve'     | 'CC81003MZ01'                |'EC178_394_394SXA_H414'| '1000U'  | '16V'         | '20%'       | 'IO'       | 'CAP OSCON SMD 1000U 16V(20%,ESR18,10*10)'             | 'SMT'          | ''          | ''            | '20181119'
 '3900U'  | '16V'   | '20%'       | 'THLF'      | ''         | 'CC83903MD05'(!)             = ''              | ''                 | 'CC83903MD05'                |'EC197_493_493_R'| '3900U'  | '16V'         | '20%'       | 'DISCRETE' | 'CAP ELEC DIP 3900U 16V(20%,12.5*30)NPN'               | 'DIP'          | ''          | ''            | '20190107'
 '3900U'  | '16V'   | '20%'       | 'THLF'      | 'EMPTY'    | 'CC83903MD05'(!)             = ''              | ''                 | 'CC83903MD05'                |'EC197_493_493_R'| '3900U'  | '16V'         | '20%'       | 'IO'       | 'CAP ELEC DIP 3900U 16V(20%,12.5*30)NPN'               | 'DIP'          | ''          | ''            | '20190107'
 '25F'    | '3V'    | '30%'       | 'THLF'      | ''         | 'CCC250KTD02'(!)             = ''              | ''                 | 'CCC250KTD02'                |'EC296_650_650_R'| '25F'    | '3V'          | '30%'       | 'DISCRETE' | 'CAP ELEC DIP 25F 3V(-10/+30%,16*25)SUPER'             | 'DIP'          | ''          | ''            | '20190107'
 '25F'    | '3V'    | '30%'       | 'THLF'      | 'EMPTY'    | 'CCC250KTD02'(!)             = ''              | ''                 | 'CCC250KTD02'                |'EC296_650_650_R'| '25F'    | '3V'          | '30%'       | 'IO'       | 'CAP ELEC DIP 25F 3V(-10/+30%,16*25)SUPER'             | 'DIP'          | ''          | ''            | '20190107'
 '560U'   | '100V'  | '20%'       | 'THLF'      | 'ALUM'     | 'CC75608MD01'(!)             = ''              | ''                 | 'CC75608MD01'                |'EC7-5_18-5_26-5'| '560U'   | '100V'        | '20%'       | 'DISCRETE' | 'CAP ELEC DIP 560U 100V(20%,18*25)'                    | 'DIP'          | ''          | ''            | '20190110'
 '560U'   | '100V'  | '20%'       | 'THLF'      | 'EMPTY'    | 'CC75608MD01'(!)             = ''              | ''                 | 'CC75608MD01'                |'EC7-5_18-5_26-5'| '560U'   | '100V'        | '20%'       | 'IO'       | 'CAP ELEC DIP 560U 100V(20%,18*25)'                    | 'DIP'          | ''          | ''            | '20190110'
 '3900U'  | '16V'   | '20%'       | 'THLF'      | ''         | 'CC83903MD06'(!)             = ''              | ''                 | 'CC83903MD06'                |'EC197_493_493_RXA'| '3900U'  | '16V'         | '20%'       | 'DISCRETE' | 'CAP ELEC DIP 3900U 16V(20%,12.5*30)MAT'               | 'DIP'          | ''          | ''            | '20190110'
 '3900U'  | '16V'   | '20%'       | 'THLF'      | 'EMPTY'    | 'CC83903MD06'(!)             = ''              | ''                 | 'CC83903MD06'                |'EC197_493_493_RXA'| '3900U'  | '16V'         | '20%'       | 'IO'       | 'CAP ELEC DIP 3900U 16V(20%,12.5*30)MAT'               | 'DIP'          | ''          | ''            | '20190110'
 '3900U'  | '16V'   | '20%'       | 'THLF'      | ''         | 'CC83903MD04'(!)             = ''              | ''                 | 'CC83903MD04'                |'EC197_493_493_R'| '3900U'  | '16V'         | '20%'       | 'DISCRETE' | 'CAP ELEC DIP 3900U 16V(20%,12.5*30)'                  | 'DIP'          | ''          | ''            | '20190110'
 '3900U'  | '16V'   | '20%'       | 'THLF'      | 'EMPTY'    | 'CC83903MD04'(!)             = ''              | ''                 | 'CC83903MD04'                |'EC197_493_493_R'| '3900U'  | '16V'         | '20%'       | 'IO'       | 'CAP ELEC DIP 3900U 16V(20%,12.5*30)'                  | 'DIP'          | ''          | ''            | '20190110'
 '47U'    | '20V'   | '20%'       | 'SMLF'      | 'ALUM'     | 'CC6470HMZ02'(!)             = 'End of Design' | 'Comp-Approve'     | 'CC6470HMZ02'                |'EC75_248_174S'| '47UF'   | '20V'         | '20%'       | 'DISCRETE' | 'CAP ELEC SMD 47U 20V(20%,6.3*4.4)NPN'                 | 'SMT'          | ''          | ''            | '20190116'
 '47U'    | '20V'   | '20%'       | 'SMLF'      | 'EMPTY'    | 'CC6470HMZ02'(!)             = 'End of Design' | 'Comp-Approve'     | 'CC6470HMZ02'                |'EC75_248_174S'| '47UF'   | '20V'         | '20%'       | 'IO'       | 'CAP ELEC SMD 47U 20V(20%,6.3*4.4)NPN'                 | 'SMT'          | ''          | ''            | '20190116'
 '330UF'  | '100V'  | '20%'       | 'SMLF'      | 'ALUM'     | 'CC73308MZ00'(!)             = ''              | ''                 | 'CC73308MZ00'                |'EC264_709_650S_H670'| '330UF'  | '100V'        | '20%'       | 'DISCRETE' | 'CAP ELEC SMD 330U 100V(20%,18*16.5)AEC'               | 'SMT'          | ''          | ''            | '20190212'
 '330UF'  | '100V'  | '20%'       | 'SMLF'      | 'EMPTY'    | 'CC73308MZ00'(!)             = ''              | ''                 | 'CC73308MZ00'                |'EC264_709_650S_H670'| '330UF'  | '100V'        | '20%'       | 'IO'       | 'CAP ELEC SMD 330U 100V(20%,18*16.5)AEC'               | 'SMT'          | ''          | ''            | '20190212'
 '47U'    | '80V'   | '20%'       | 'SMLF'      | 'ALUM'     | 'CC6470EMZ01'(!)             = ''              | ''                 | 'CC6470EMZ01'                |'EC181_394_496SXA'| '47U'    | '80V'         | '20%'       | 'DISCRETE' | 'CAP OSCON SMD 47U 80V(20%,ESR28,10*12.6)'             | 'SMT'          | ''          | ''            | '20190215'
 '47U'    | '80V'   | '20%'       | 'SMLF'      | 'EMPTY'    | 'CC6470EMZ01'(!)             = ''              | ''                 | 'CC6470EMZ01'                |'EC181_394_496SXA'| '47U'    | '80V'         | '20%'       | 'IO'       | 'CAP OSCON SMD 47U 80V(20%,ESR28,10*12.6)'             | 'SMT'          | ''          | ''            | '20190215'
 '560UF'  | '16V'   | '20%'       | 'THLF'      | 'OSCON'    | 'CC75603MD01'(!)             = ''              | ''                 | 'CC75603MD01'                |'EC98_248_433XA'| '560UF'  | '16V'         | '20%'       | 'DISCRETE' | 'CAP OSCON DIP 560U 16V(20%,ESR20,6.3*11)'             | 'DIP'          | ''          | ''            | '20190521'
 '560UF'  | '16V'   | '20%'       | 'THLF'      | 'EMPTY'    | 'CC75603MD01'(!)             = ''              | ''                 | 'CC75603MD01'                |'EC98_248_433XA'| '560UF'  | '16V'         | '20%'       | 'IO'       | 'CAP OSCON DIP 560U 16V(20%,ESR20,6.3*11)'             | 'DIP'          | ''          | ''            | '20190521'
 '220UF'  | '25V'   | '20%'       | 'THLF'      | 'OSCON'    | 'CC72204MD02'(!)             = ''              | ''                 | 'CC72204MD02'                |'EC3-5_8-5_13XA'| '220UF'  | '25V'         | '20%'       | 'DISCRETE' | 'CAP OSCON DIP 220U 25V(20%,8*11.5)NPN'                | 'DIP'          | ''          | ''            | '20190625'
 '220UF'  | '25V'   | '20%'       | 'THLF'      | 'EMPTY'    | 'CC72204MD02'(!)             = ''              | ''                 | 'CC72204MD02'                |'EC3-5_8-5_13XA'| '220UF'  | '25V'         | '20%'       | 'IO'       | 'CAP OSCON DIP 220U 25V(20%,8*11.5)NPN'                | 'DIP'          | ''          | ''            | '20190625'
 '220UF'  | '25V'   | '20%'       | 'THLF'      | 'OSCON'    | 'SP_CC72204MD02'(!)          = ''              | ''                 | 'CC72204MD02'                |'G_EC3-5_8-5_13XA'| '220UF'  | '25V'         | '20%'       | 'DISCRETE' | 'CAP OSCON DIP 220U 25V(20%,8*11.5)NPN_FOR SEL'        | 'DIP'          | ''          | ''            | '20190625'
 '220UF'  | '25V'   | '20%'       | 'THLF'      | 'EMPTY'    | 'SP_CC72204MD02'(!)          = ''              | ''                 | 'CC72204MD02'                |'G_EC3-5_8-5_13XA'| '220UF'  | '25V'         | '20%'       | 'IO'       | 'CAP OSCON DIP 220U 25V(20%,8*11.5)NPN_FOR SEL'        | 'DIP'          | ''          | ''            | '20190625'
 '100UF'  | '16V'   | '+10/-35%'  | 'SMLF'      | 'ALUM'     | 'CC71003TZ01'(!)             = ''              | ''                 | 'CC71003TZ01'                |'EC56_197_233S'| '100UF'  | '16V'         | '+10/-35%'  | 'DISCRETE' | 'CAPOSCON SMD 100U 16V(+10/-35%,5*5.9)SAY'             | 'SMT'          | ''          | ''            | '20190625'
 '100UF'  | '16V'   | '+10/-35%'  | 'SMLF'      | 'EMPTY'    | 'CC71003TZ01'(!)             = ''              | ''                 | 'CC71003TZ01'                |'EC56_197_233S'| '100UF'  | '16V'         | '+10/-35%'  | 'IO'       | 'CAPOSCON SMD 100U 16V(+10/-35%,5*5.9)SAY'             | 'SMT'          | ''          | ''            | '20190625'
 '330UF'  | '16V'   | '20%'       | 'SMLF'      | 'OSCON'    | 'CC73303MZ06'(!)             = ''              | ''                 | 'CC73303MZ06'                |'EC126_315_272SXA'| '330UF'  | '16V'         | '20%'       | 'DISCRETE' | 'CAP OSCON SMD 330U 16V(20%,8*6.9)'                    | 'SMT'          | ''          | ''            | '20190626'
 '330UF'  | '16V'   | '20%'       | 'SMLF'      | 'EMPTY'    | 'CC73303MZ06'(!)             = ''              | ''                 | 'CC73303MZ06'                |'EC126_315_272SXA'| '330UF'  | '16V'         | '20%'       | 'IO'       | 'CAP OSCON SMD 330U 16V(20%,8*6.9)'                    | 'SMT'          | ''          | ''            | '20190626'
 '27UF'   | '80V'   | '20%'       | 'SMLF'      | 'OSCON'    | 'CC6270EMZ00'(!)             = ''              | ''                 | 'CC6270EMZ00'                |'EC181_394_311SXA'| '27UF'   | '80V'         | '20%'       | 'DISCRETE' | 'CAP OSCON SMD 27U 80V(20%,10*7.9)'                    | 'SMT'          | ''          | ''            | '20190626'
 '27UF'   | '80V'   | '20%'       | 'SMLF'      | 'EMPTY'    | 'CC6270EMZ00'(!)             = ''              | ''                 | 'CC6270EMZ00'                |'EC181_394_311SXA'| '27UF'   | '80V'         | '20%'       | 'IO'       | 'CAP OSCON SMD 27U 80V(20%,10*7.9)'                    | 'SMT'          | ''          | ''            | '20190626'
 '220UF'  | '25V'   | '20%'       | 'THLF'      | 'OSCON'    | 'CC72204MD01'(!)             = ''              | ''                 | 'CC72204MD01'                |'EC138_315_453XB'| '220UF'  | '25V'         | '20%'       | 'DISCRETE' | 'CAP OSCON DIP 220U 25V(20%,8*11.5)APQ'                | 'DIP'          | ''          | ''            | '20190627'
 '220UF'  | '25V'   | '20%'       | 'THLF'      | 'EMPTY'    | 'CC72204MD01'(!)             = ''              | ''                 | 'CC72204MD01'                |'EC138_315_453XB'| '220UF'  | '25V'         | '20%'       | 'IO'       | 'CAP OSCON DIP 220U 25V(20%,8*11.5)APQ'                | 'DIP'          | ''          | ''            | '20190627'
 '270UF'  | '16V'   | '20%'       | 'SMLF'      | 'OSCON'    | 'CC72703MZ06'(!)             = 'End of Design' | 'Comp-Approve'     | 'CC72703MZ06'                |'EC75_248_382S'| '270UF'  | '16V'         | '20%'       | 'DISCRETE' | 'CAP OSCON SMD 270U 16V(20%,6.3*9.7)NPN'               | 'SMT'          | ''          | ''            | '20190627'
 '270UF'  | '16V'   | '20%'       | 'SMLF'      | 'EMPTY'    | 'CC72703MZ06'(!)             = 'End of Design' | 'Comp-Approve'     | 'CC72703MZ06'                |'EC75_248_382S'| '270UF'  | '16V'         | '20%'       | 'IO'       | 'CAP OSCON SMD 270U 16V(20%,6.3*9.7)NPN'               | 'SMT'          | ''          | ''            | '20190627'
 '270UF'  | '16V'   | '20%'       | 'SMLF'      | 'OSCON'    | 'CC72703MZ07'(!)             = ''              | ''                 | 'CC72703MZ07'                |'EC83_248_390S'| '270UF'  | '16V'         | '20%'       | 'DISCRETE' | 'CAP OSCON SMD 270U 16V(20%,6.3*9.9)SAY'               | 'SMT'          | ''          | ''            | '20190627'
 '270UF'  | '16V'   | '20%'       | 'SMLF'      | 'EMPTY'    | 'CC72703MZ07'(!)             = ''              | ''                 | 'CC72703MZ07'                |'EC83_248_390S'| '270UF'  | '16V'         | '20%'       | 'IO'       | 'CAP OSCON SMD 270U 16V(20%,6.3*9.9)SAY'               | 'SMT'          | ''          | ''            | '20190627'
 '100UF'  | '16V'   | '20%'       | 'SMLF'      | 'OSCON'    | 'CC71003MZ30'(!)             = ''              | ''                 | 'CC71003MZ30'                |'EC56_197_229SXA'| '100UF'  | '16V'         | '20%'       | 'DISCRETE' | 'CAP OSCON SMD 100U 16V(20%,5*5.8)NPN'                 | 'SMT'          | ''          | ''            | '20190627'
 '100UF'  | '16V'   | '20%'       | 'SMLF'      | 'EMPTY'    | 'CC71003MZ30'(!)             = ''              | ''                 | 'CC71003MZ30'                |'EC56_197_229SXA'| '100UF'  | '16V'         | '20%'       | 'IO'       | 'CAP OSCON SMD 100U 16V(20%,5*5.8)NPN'                 | 'SMT'          | ''          | ''            | '20190627'
 '100UF'  | '16V'   | '+10/-35%'  | 'SMLF'      | 'OSCON'    | 'CC71003TZ00'(!)             = ''              | ''                 | 'CC71003TZ00'                |'EC56_197_233S'| '100UF'  | '16V'         | '+10/-35%'  | 'DISCRETE' | 'CAPOSCONSMD 100U 16V(+10/-35%,105C,5*5.9'             | 'SMT'          | ''          | ''            | '20190627'
 '100UF'  | '16V'   | '+10/-35%'  | 'SMLF'      | 'EMPTY'    | 'CC71003TZ00'(!)             = ''              | ''                 | 'CC71003TZ00'                |'EC56_197_233S'| '100UF'  | '16V'         | '+10/-35%'  | 'IO'       | 'CAPOSCONSMD 100U 16V(+10/-35%,105C,5*5.9'             | 'SMT'          | ''          | ''            | '20190627'
 '560UF'  | '16V'   | '20%'       | 'SMLF'      | 'OSCON'    | 'CC75603MZ01'(!)             = ''              | ''                 | 'CC75603MZ01'                |'EC126_315_461S'| '560UF'  | '16V'         | '20%'       | 'DISCRETE' | 'CAP OSCON SMD 560U 16V(20%,105C,8*11.7)'              | 'SMT'          | ''          | ''            | '20190628'
 '560UF'  | '16V'   | '20%'       | 'SMLF'      | 'EMPTY'    | 'CC75603MZ01'(!)             = ''              | ''                 | 'CC75603MZ01'                |'EC126_315_461S'| '560UF'  | '16V'         | '20%'       | 'IO'       | 'CAP OSCON SMD 560U 16V(20%,105C,8*11.7)'              | 'SMT'          | ''          | ''            | '20190628'
 '560UF'  | '6.3V'  | '20%'       | 'THLF'      | 'OSCON'    | 'CC75601MD16'(!)             = ''              | ''                 | 'CC75601MD16'                |'EC2-5_6-8_9-5'| '560UF'  | '6.3V'        | '20%'       | 'DISCRETE' | 'CAP OSCON DIP 560U 6.3V(+-20%,6.3*8)NPN'              | 'DIP'          | ''          | ''            | '20190701'
 '560UF'  | '6.3V'  | '20%'       | 'THLF'      | 'EMPTY'    | 'CC75601MD16'(!)             = ''              | ''                 | 'CC75601MD16'                |'EC2-5_6-8_9-5'| '560UF'  | '6.3V'        | '20%'       | 'IO'       | 'CAP OSCON DIP 560U 6.3V(+-20%,6.3*8)NPN'              | 'DIP'          | ''          | ''            | '20190701'
 '560UF'  | '6.3V'  | '20%'       | 'THLF'      | 'OSCON'    | 'CC75601MD03'(!)             = ''              | ''                 | 'CC75601MD03'                |'EC98_248_315XB'| '560UF'  | '6.3V'        | '20%'       | 'DISCRETE' | 'CAP OSCON DIP 560U 6.3V(+-20%,6.3*8)'                 | 'DIP'          | ''          | ''            | '20190701'
 '560UF'  | '6.3V'  | '20%'       | 'THLF'      | 'EMPTY'    | 'CC75601MD03'(!)             = ''              | ''                 | 'CC75601MD03'                |'EC98_248_315XB'| '560UF'  | '6.3V'        | '20%'       | 'IO'       | 'CAP OSCON DIP 560U 6.3V(+-20%,6.3*8)'                 | 'DIP'          | ''          | ''            | '20190701'
 '270UF'  | '16V'   | '20%'       | 'THLF'      | 'OSCON'    | 'CC72703MD38'(!)             = ''              | ''                 | 'CC72703MD38'                |'EC2-5_6-8_9-2'| '270UF'  | '16V'         | '20%'       | 'DISCRETE' | 'CAPOSCON DIP 270U16V(20%,ESR10,6.3*8)NPN'             | 'DIP'          | ''          | ''            | '20190701'
 '270UF'  | '16V'   | '20%'       | 'THLF'      | 'EMPTY'    | 'CC72703MD38'(!)             = ''              | ''                 | 'CC72703MD38'                |'EC2-5_6-8_9-2'| '270UF'  | '16V'         | '20%'       | 'IO'       | 'CAPOSCON DIP 270U16V(20%,ESR10,6.3*8)NPN'             | 'DIP'          | ''          | ''            | '20190701'
 '560UF'  | '2.5V'  | '20%'       | 'THLF'      | 'OSCON'    | 'CC7560JMD16'(!)             = 'End of Design' | 'Comp-Approve'     | 'CC7560JMD16'                |'EC2_5-5_9XB'| '560UF'  | '2.5V'        | '20%'       | 'DISCRETE' | 'CAP OSCON DIP 560U 2.5V(20%,5*8)SAY'                  | 'DIP'          | ''          | ''            | '20190701'
 '560UF'  | '2.5V'  | '20%'       | 'THLF'      | 'EMPTY'    | 'CC7560JMD16'(!)             = 'End of Design' | 'Comp-Approve'     | 'CC7560JMD16'                |'EC2_5-5_9XB'| '560UF'  | '2.5V'        | '20%'       | 'IO'       | 'CAP OSCON DIP 560U 2.5V(20%,5*8)SAY'                  | 'DIP'          | ''          | ''            | '20190701'
 '560UF'  | '2.5V'  | '20%'       | 'THLF'      | 'OSCON'    | 'SP_CC7560JMD16'(!)          = 'End of Design' | 'Comp-Approve'     | 'CC7560JMD16'                |'G_EC2_5-5_9XB'| '560UF'  | '2.5V'        | '20%'       | 'DISCRETE' | 'CAP OSCON DIP 560U 2.5V(20%,5*8)SAY_FOR SEL'          | 'DIP'          | ''          | ''            | '20190701'
 '560UF'  | '2.5V'  | '20%'       | 'THLF'      | 'EMPTY'    | 'SP_CC7560JMD16'(!)          = 'End of Design' | 'Comp-Approve'     | 'CC7560JMD16'                |'G_EC2_5-5_9XB'| '560UF'  | '2.5V'        | '20%'       | 'IO'       | 'CAP OSCON DIP 560U 2.5V(20%,5*8)SAY_FOR SEL'          | 'DIP'          | ''          | ''            | '20190701'
 '330UF'  | '6.3V'  | '20%'       | 'SMLF'      | 'POSCAP'   | 'CH7331MI806'(!)             = ''              | ''                 | 'CH7331MI806'                |'TAJ_D2EXA'| '330UF'  | '6.3V'        | '20%'       | 'DISCRETE' | 'CAP CHIP 330U 6.3V(20%,POSCAP,7343)SAY'               | 'SMT'          | ''          | ''            | '20190703'
 '330UF'  | '6.3V'  | '20%'       | 'SMLF'      | 'EMPTY'    | 'CH7331MI806'(!)             = ''              | ''                 | 'CH7331MI806'                |'TAJ_D2EXA'| '330UF'  | '6.3V'        | '20%'       | 'IO'       | 'CAP CHIP 330U 6.3V(20%,POSCAP,7343)SAY'               | 'SMT'          | ''          | ''            | '20190703'
 '330UF'  | '6.3V'  | '20%'       | 'SMLF'      | 'POSCAP'   | 'CH7331MI805'(!)             = 'End of Design' | 'Comp-Approve'     | 'CH7331MI805'                |'TAJ_7343-20'| '330UF'  | '6.3V'        | '20%'       | 'DISCRETE' | 'CAP CHIP 330U 6.3V(20%,POSCAP,7343)KEM'               | 'SMT'          | ''          | ''            | '20190710'
 '330UF'  | '6.3V'  | '20%'       | 'SMLF'      | 'EMPTY'    | 'CH7331MI805'(!)             = 'End of Design' | 'Comp-Approve'     | 'CH7331MI805'                |'TAJ_7343-20'| '330UF'  | '6.3V'        | '20%'       | 'IO'       | 'CAP CHIP 330U 6.3V(20%,POSCAP,7343)KEM'               | 'SMT'          | ''          | ''            | '20190710'
 '56UF'   | '100V'  | '20%'       | 'THLF'      | 'ALUM'     | 'CC65608MD03'(!)             = ''              | ''                 | 'CC65608MD03'                |'EC197_394_492XA'| '56UF'   | '100V'        | '20%'       | 'DISCRETE' | 'CAP ELEC DIP 56U 100V(20%,105C,10*12.5)'              | 'DIP'          | ''          | ''            | '20190711'
 '56UF'   | '100V'  | '20%'       | 'THLF'      | 'EMPTY'    | 'CC65608MD03'(!)             = ''              | ''                 | 'CC65608MD03'                |'EC197_394_492XA'| '56UF'   | '100V'        | '20%'       | 'IO'       | 'CAP ELEC DIP 56U 100V(20%,105C,10*12.5)'              | 'DIP'          | ''          | ''            | '20190711'
 '56UF'   | '100V'  | '20%'       | 'THLF'      | 'ALUM'     | 'SP_CC65608MD03'(!)          = ''              | ''                 | 'CC65608MD03'                |'G_EC197_394_492XA'| '56UF'   | '100V'        | '20%'       | 'DISCRETE' | 'CAP ELEC DIP 56U 100V(20%,105C,10*12.5)_FOR SEL'      | 'DIP'          | ''          | ''            | '20190711'
 '56UF'   | '100V'  | '20%'       | 'THLF'      | 'EMPTY'    | 'SP_CC65608MD03'(!)          = ''              | ''                 | 'CC65608MD03'                |'G_EC197_394_492XA'| '56UF'   | '100V'        | '20%'       | 'IO'       | 'CAP ELEC DIP 56U 100V(20%,105C,10*12.5)_FOR SEL'      | 'DIP'          | ''          | ''            | '20190711'
 '330UF'  | '2V'    | '+10/-35%'  | 'SMLF'      | 'SPCAP'    | 'CH733RY8809'(!)             = 'End of Design' | 'End of Life'      | 'CH733RY8809'                |'TAJ_SX_EOL'| '330UF'  | '2V'          | '+10/-35%'  | 'DISCRETE' | 'CAP CHIP 330U 2V(+10/-35%,SPCAP,7343)MUR'             | 'SMT'          | ''          | ''            | '20190723'
 '330UF'  | '2V'    | '+10/-35%'  | 'SMLF'      | 'EMPTY'    | 'CH733RY8809'(!)             = 'End of Design' | 'End of Life'      | 'CH733RY8809'                |'TAJ_SX_EOL'| '330UF'  | '2V'          | '+10/-35%'  | 'IO'       | 'CAP CHIP 330U 2V(+10/-35%,SPCAP,7343)MUR'             | 'SMT'          | ''          | ''            | '20190723'
 '56UF'   | '100V'  | '20%'       | 'THLF'      | 'ALUM'     | 'CC65608MD04'(!)             = ''              | ''                 | 'CC65608MD04'                |'G_EC197_394_492XA'| '56UF'   | '100V'        | '20%'       | 'DISCRETE' | 'CAP ELEC 56UF 100V(20%,10*12.5)SEL ASS'               | 'DIP'          | ''          | ''            | '20190724'
 '56UF'   | '100V'  | '20%'       | 'THLF'      | 'EMPTY'    | 'CC65608MD04'(!)             = ''              | ''                 | 'CC65608MD04'                |'G_EC197_394_492XA'| '56UF'   | '100V'        | '20%'       | 'IO'       | 'CAP ELEC 56UF 100V(20%,10*12.5)SEL ASS'               | 'DIP'          | ''          | ''            | '20190724'
 '270UF'  | '16V'   | '20%'       | 'THLF'      | 'OSCON'    | 'CC72703MD39'(!)             = ''              | ''                 | 'CC72703MD39'                |'EC98_248_315XA'| '270UF'  | '16V'         | '20%'       | 'DISCRETE' | 'CAP OSCONDIP 270U16V(20%,ESR10,6.3*8)TOW'             | 'DIP'          | ''          | ''            | '20190806'
 '270UF'  | '16V'   | '20%'       | 'THLF'      | 'EMPTY'    | 'CC72703MD39'(!)             = ''              | ''                 | 'CC72703MD39'                |'EC98_248_315XA'| '270UF'  | '16V'         | '20%'       | 'IO'       | 'CAP OSCONDIP 270U16V(20%,ESR10,6.3*8)TOW'             | 'DIP'          | ''          | ''            | '20190806'
 '470UF'  | '2.5V'  | '20%'       | 'SMLF'      | 'SPCAP'    | 'CH747LM8819'(!)             = 'End of Design' | 'Comp-Approve'     | 'CH747LM8819'                |'TAJ_SX'| '470UF'  | '2.5V'        | '20%'       | 'DISCRETE' | 'CAPCHIP 470U 2.5V(20%,ESR4.5,7343,SPCAP)'             | 'SMT'          | ''          | ''            | '20190816'
 '470UF'  | '2.5V'  | '20%'       | 'SMLF'      | 'EMPTY'    | 'CH747LM8819'(!)             = 'End of Design' | 'Comp-Approve'     | 'CH747LM8819'                |'TAJ_SX'| '470UF'  | '2.5V'        | '20%'       | 'IO'       | 'CAPCHIP 470U 2.5V(20%,ESR4.5,7343,SPCAP)'             | 'SMT'          | ''          | ''            | '20190816'
 '56UF'   | '100V'  | '20%'       | 'THLF'      | 'ALUM'     | 'CC65608MD05'(!)             = ''              | ''                 | 'CC65608MD05'                |'EC5_10-5_14'| '56UF'   | '100V'        | '20%'       | 'DISCRETE' | 'CAP ELEC DIP 56U 100V(20%,10*12.5)NPN'                | 'DIP'          | ''          | ''            | '20190820'
 '56UF'   | '100V'  | '20%'       | 'THLF'      | 'EMPTY'    | 'CC65608MD05'(!)             = ''              | ''                 | 'CC65608MD05'                |'EC5_10-5_14'| '56UF'   | '100V'        | '20%'       | 'IO'       | 'CAP ELEC DIP 56U 100V(20%,10*12.5)NPN'                | 'DIP'          | ''          | ''            | '20190820'
 '56UF'   | '100V'  | '20%'       | 'THLF'      | 'ALUM'     | 'SP_CC65608MD05'(!)          = ''              | ''                 | 'CC65608MD05'                |'G_EC5_10-5_14'| '56UF'   | '100V'        | '20%'       | 'DISCRETE' | 'CAP ELEC DIP 56U 100V(20%,10*12.5)NPN)_FOR SEL'       | 'DIP'          | ''          | ''            | '20190820'
 '56UF'   | '100V'  | '20%'       | 'THLF'      | 'EMPTY'    | 'SP_CC65608MD05'(!)          = ''              | ''                 | 'CC65608MD05'                |'G_EC5_10-5_14'| '56UF'   | '100V'        | '20%'       | 'IO'       | 'CAP ELEC DIP 56U 100V(20%,10*12.5)NPN)_FOR SEL'       | 'DIP'          | ''          | ''            | '20190820'
 '1000UF' | '16V'   | '20%'       | 'SMLF'      | 'OSCON'    | 'CC81003MZ03'(!)             = ''              | ''                 | 'CC81003MZ03'                |'EC181_394_496SXA'| '1000UF' | '16V'         | '20%'       | 'DISCRETE' | 'CAP OSCON SMD 1000U 16V(20%,10*12.6)SAY'              | 'SMT'          | ''          | ''            | '20190906'
 '1000UF' | '16V'   | '20%'       | 'SMLF'      | 'EMPTY'    | 'CC81003MZ03'(!)             = ''              | ''                 | 'CC81003MZ03'                |'EC181_394_496SXA'| '1000UF' | '16V'         | '20%'       | 'IO'       | 'CAP OSCON SMD 1000U 16V(20%,10*12.6)SAY'              | 'SMT'          | ''          | ''            | '20190906'
 '2200UF' | '16V'   | '20%'       | 'THLF'      | 'OSCON'    | 'CC82202MD01'(!)             = ''              | ''                 | 'CC82202MD01'                |'EC5_10-5_21-5XA'| '2200UF' | '16V'         | '20%'       | 'DISCRETE' | 'CAP OSCON DIP 2200U 16V(20%,105C,10*20)'              | 'DIP'          | ''          | ''            | '20161021'
 '2200UF' | '16V'   | '20%'       | 'THLF'      | 'EMPTY'    | 'CC82202MD01'(!)             = ''              | ''                 | 'CC82202MD01'                |'EC5_10-5_21-5XA'| '2200UF' | '16V'         | '20%'       | 'IO'       | 'CAP OSCON DIP 2200U 16V(20%,105C,10*20)'              | 'DIP'          | ''          | ''            | '20161021'
 '2200UF' | '16V'   | '20%'       | 'THLF'      | 'OSCON'    | 'SP_CC82202MD01'(!)          = ''              | ''                 | 'CC82202MD01'                |'G_EC5_10-5_21-5XA'| '2200UF' | '16V'         | '20%'       | 'DISCRETE' | 'CAP OSCON DIP 2200U 16V(20%,105C,10*20)_FOR SEL'      | 'DIP'          | ''          | ''            | '20190912'
 '2200UF' | '16V'   | '20%'       | 'THLF'      | 'EMPTY'    | 'SP_CC82202MD01'(!)          = ''              | ''                 | 'CC82202MD01'                |'G_EC5_10-5_21-5XA'| '2200UF' | '16V'         | '20%'       | 'IO'       | 'CAP OSCON DIP 2200U 16V(20%,105C,10*20)_FOR SEL'      | 'DIP'          | ''          | ''            | '20190912'
 '330UF'  | '6.3V'  | '20%'       | 'SMLF'      | 'OSCON'    | 'CC73301MZ20'(!)             = ''              | ''                 | 'CC73301MZ20'                |'EC83_248_233S'| '330UF'  | '6.3V'        | '20%'       | 'DISCRETE' | 'CAP OSCON 330U 6.3V(20%,105C,6.3*5.9)SAY'             | 'SMT'          | ''          | ''            | '20190925'
 '330UF'  | '6.3V'  | '20%'       | 'SMLF'      | 'EMPTY'    | 'CC73301MZ20'(!)             = ''              | ''                 | 'CC73301MZ20'                |'EC83_248_233S'| '330UF'  | '6.3V'        | '20%'       | 'IO'       | 'CAP OSCON 330U 6.3V(20%,105C,6.3*5.9)SAY'             | 'SMT'          | ''          | ''            | '20190925'
 '47UF'   | '80V'   | '20%'       | 'SMLF'      | 'OSCON'    | 'CC6470EMZ02'(!)             = ''              | ''                 | 'CC6470EMZ02'                |'EC181_394_496SXA'| '47UF'   | '80V'         | '20%'       | 'DISCRETE' | 'CAP OSCON SMD 47U 80V(20%,10*12.6)SAY'                | 'SMT'          | ''          | ''            | '20191002'
 '47UF'   | '80V'   | '20%'       | 'SMLF'      | 'EMPTY'    | 'CC6470EMZ02'(!)             = ''              | ''                 | 'CC6470EMZ02'                |'EC181_394_496SXA'| '47UF'   | '80V'         | '20%'       | 'IO'       | 'CAP OSCON SMD 47U 80V(20%,10*12.6)SAY'                | 'SMT'          | ''          | ''            | '20191002'
 '560UF'  | '16V'   | '20%'       | 'SMLF'      | 'OSCON'    | 'CC75603MZ07'(!)             = 'End of Design' | 'Comp-Approve'     | 'CC75603MZ07'                |'EC122_315_394S'| '560UF'  | '16V'         | '20%'       | 'DISCRETE' | 'CAPOSCON SMD 560U 16V(20%,ESR18,8*10)NPN'             | 'SMT'          | ''          | ''            | '20191030'
 '560UF'  | '16V'   | '20%'       | 'SMLF'      | 'EMPTY'    | 'CC75603MZ07'(!)             = 'End of Design' | 'Comp-Approve'     | 'CC75603MZ07'                |'EC122_315_394S'| '560UF'  | '16V'         | '20%'       | 'IO'       | 'CAPOSCON SMD 560U 16V(20%,ESR18,8*10)NPN'             | 'SMT'          | ''          | ''            | '20191030'
 '330UF'  | '4V'    | '20%'       | 'SMLF'      | 'SPCAP'    | 'CH733KM8805'(!)             = ''              | ''                 | 'CH733KM8805'                |'TAJ_D9'| '330UF'  | '4V'          | '20%'       | 'DISCRETE' | 'CAP CHIP 330UF 4V(20%,SPCAP,ESR8,7343)'               | 'SMT'          | ''          | ''            | '20191213'
 '330UF'  | '4V'    | '20%'       | 'SMLF'      | 'EMPTY'    | 'CH733KM8805'(!)             = ''              | ''                 | 'CH733KM8805'                |'TAJ_D9'| '330UF'  | '4V'          | '20%'       | 'IO'       | 'CAP CHIP 330UF 4V(20%,SPCAP,ESR8,7343)'               | 'SMT'          | ''          | ''            | '20191213'
 '100UF'  | '6.3V'  | '20%'       | 'SMLF'      | 'TANT'     | 'CH7101MI604'(!)             = ''              | ''                 | 'CH7101MI604'                |'TAJ_B_T520B227M2R5ATE015'| '100UF'  | '6.3V'        | '20%'       | 'DISCRETE' | 'CAPCHIP100U 6.3V(20%POSCAP(TAN),3528)KEM'             | 'SMT'          | ''          | ''            | '20191220'
 '100UF'  | '6.3V'  | '20%'       | 'SMLF'      | 'EMPTY'    | 'CH7101MI604'(!)             = ''              | ''                 | 'CH7101MI604'                |'TAJ_B_T520B227M2R5ATE015'| '100UF'  | '6.3V'        | '20%'       | 'IO'       | 'CAPCHIP100U 6.3V(20%POSCAP(TAN),3528)KEM'             | 'SMT'          | ''          | ''            | '20191220'
 '270UF'  | '2V'    | '20%'       | 'SMLF'      | 'POSCAP'   | 'CH727RMI600'(!)             = ''              | ''                 | 'CH727RMI600'                |'TAJ_B2S'| '270UF'  | '2V'          | '20%'       | 'DISCRETE' | 'CAPCHIP 270U 2V(20%,ESR6,POSCAP,3528)SAY'             | 'SMT'          | ''          | ''            | '20200102'
 '270UF'  | '2V'    | '20%'       | 'SMLF'      | 'EMPTY'    | 'CH727RMI600'(!)             = ''              | ''                 | 'CH727RMI600'                |'TAJ_B2S'| '270UF'  | '2V'          | '20%'       | 'IO'       | 'CAPCHIP 270U 2V(20%,ESR6,POSCAP,3528)SAY'             | 'SMT'          | ''          | ''            | '20200102'
 '2200UF' | '16V'   | '20%'       | 'THLF'      | 'OSCON'    | 'CC82203MD07'(!)             = ''              | ''                 | 'CC82203MD07'                |'EC5_10-5_21-5XA'| '2200UF' | '16V'         | '20%'       | 'DISCRETE' | 'CAP OSCON DIP 2200U 16V(20%,10*20)NPN'                | 'DIP'          | ''          | ''            | '20200120'
 '2200UF' | '16V'   | '20%'       | 'THLF'      | 'EMPTY'    | 'CC82203MD07'(!)             = ''              | ''                 | 'CC82203MD07'                |'EC5_10-5_21-5XA'| '2200UF' | '16V'         | '20%'       | 'IO'       | 'CAP OSCON DIP 2200U 16V(20%,10*20)NPN'                | 'DIP'          | ''          | ''            | '20200120'
 '270UF'  | '16V'   | '20%'       | 'THLF'      | 'OSCON'    | 'CC72703MD40'(!)             = ''              | ''                 | 'CC72703MD40'                |'EC138_315_315XA'| '270UF'  | '16V'         | '20%'       | 'DISCRETE' | 'CAP OSCON DIP 270U 16V(20%,ESR10,8*8)APQ'             | 'DIP'          | ''          | ''            | '20200121'
 '270UF'  | '16V'   | '20%'       | 'THLF'      | 'EMPTY'    | 'CC72703MD40'(!)             = ''              | ''                 | 'CC72703MD40'                |'EC138_315_315XA'| '270UF'  | '16V'         | '20%'       | 'IO'       | 'CAP OSCON DIP 270U 16V(20%,ESR10,8*8)APQ'             | 'DIP'          | ''          | ''            | '20200121'
 '330UF'  | '35V'   | '20%'       | 'SMLF'      | 'ALUM'     | 'CC73305MZ24'(!)             = ''              | ''                 | 'CC73305MZ24'                |'EC178_394_394SXB'| '330UF'  | '35V'         | '20%'       | 'DISCRETE' | 'CAP ELEC 330U 35V(20%,105C,10*10)SMD'                 | 'SMT'          | ''          | ''            | '20200203'
 '330UF'  | '35V'   | '20%'       | 'SMLF'      | 'EMPTY'    | 'CC73305MZ24'(!)             = ''              | ''                 | 'CC73305MZ24'                |'EC178_394_394SXB'| '330UF'  | '35V'         | '20%'       | 'IO'       | 'CAP ELEC 330U 35V(20%,105C,10*10)SMD'                 | 'SMT'          | ''          | ''            | '20200203'
 '1500UF' | '16V'   | '20%'       | 'THLF'      | 'ALUM'     | 'CC81503MD00'(!)             = ''              | ''                 | 'CC81503MD00'                |'EC197_394_787XC'| '1500UF' | '16V'         | '20%'       | 'DISCRETE' | 'CAP DIP 1500U 16V(+-20%,105C,10*20)'                  | 'DIP'          | ''          | ''            | '20200213'
 '1500UF' | '16V'   | '20%'       | 'THLF'      | 'EMPTY'    | 'CC81503MD00'(!)             = ''              | ''                 | 'CC81503MD00'                |'EC197_394_787XC'| '1500UF' | '16V'         | '20%'       | 'IO'       | 'CAP DIP 1500U 16V(+-20%,105C,10*20)'                  | 'DIP'          | ''          | ''            | '20200213'
 '330UF'  | '2.5V'  | '20%'       | 'SMLF'      | 'POSCAP'   | 'CH733LMI602'(!)             = 'End of Design' | 'Comp-Approve'     | 'CH733LMI602'                |'TAJ_B2XA'| '330UF'  | '2.5V'        | '20%'       | 'DISCRETE' | 'CAP CHIP 330U 2.5V(+-20%,3528,POSCAP)NEC'             | 'SMT'          | ''          | ''            | '20200226'
 '330UF'  | '2.5V'  | '20%'       | 'SMLF'      | 'EMPTY'    | 'CH733LMI602'(!)             = 'End of Design' | 'Comp-Approve'     | 'CH733LMI602'                |'TAJ_B2XA'| '330UF'  | '2.5V'        | '20%'       | 'IO'       | 'CAP CHIP 330U 2.5V(+-20%,3528,POSCAP)NEC'             | 'SMT'          | ''          | ''            | '20200226'
 '330UF'  | '2.5V'  | '20%'       | 'SMLF'      | 'POSCAP'   | 'CH733LMI603'(!)             = ''              | ''                 | 'CH733LMI603'                |'TAJ_B2S'| '330UF'  | '2.5V'        | '20%'       | 'DISCRETE' | 'CAP CHIP 330U 2.5V(+-20%,3528,POSCAP)SAY'             | 'SMT'          | ''          | ''            | '20200226'
 '330UF'  | '2.5V'  | '20%'       | 'SMLF'      | 'EMPTY'    | 'CH733LMI603'(!)             = ''              | ''                 | 'CH733LMI603'                |'TAJ_B2S'| '330UF'  | '2.5V'        | '20%'       | 'IO'       | 'CAP CHIP 330U 2.5V(+-20%,3528,POSCAP)SAY'             | 'SMT'          | ''          | ''            | '20200226'
 '220UF'  | '6.3V'  | '20%'       | 'SMLF'      | 'POSCAP'   | 'CH7221MI802'(!)             = ''              | ''                 | 'CH7221MI802'                |'TAJ_D3L'| '220UF'  | '6.3V'        | '20%'       | 'DISCRETE' | 'CAPCHIP220U 6.3V(20%,POSCAP(TAN)7343)SAY'             | 'SMT'          | ''          | ''            | '20200302'
 '220UF'  | '6.3V'  | '20%'       | 'SMLF'      | 'EMPTY'    | 'CH7221MI802'(!)             = ''              | ''                 | 'CH7221MI802'                |'TAJ_D3L'| '220UF'  | '6.3V'        | '20%'       | 'IO'       | 'CAPCHIP220U 6.3V(20%,POSCAP(TAN)7343)SAY'             | 'SMT'          | ''          | ''            | '20200302'
 '47UF'   | '25V'   | '20%'       | 'SMLF'      | 'ALUM'     | 'CC64704MZ19'(!)             = ''              | ''                 | 'CC64704MZ19'                |'EC71_248_229SXA'| '47UF'   | '25V'         | '20%'       | 'DISCRETE' | 'CAP ELEC SMD 47U 25V(20%,6.3*5.8)MAT'                 | 'SMT'          | ''          | ''            | '20200305'
 '47UF'   | '25V'   | '20%'       | 'SMLF'      | 'EMPTY'    | 'CC64704MZ19'(!)             = ''              | ''                 | 'CC64704MZ19'                |'EC71_248_229SXA'| '47UF'   | '25V'         | '20%'       | 'IO'       | 'CAP ELEC SMD 47U 25V(20%,6.3*5.8)MAT'                 | 'SMT'          | ''          | ''            | '20200305'
 '100UF'  | '25V'   | '20%'       | 'SMLF'      | 'SPCAP'    | 'CH7104M8800'(!)             = 'End of Design' | 'End of Life'      | 'CH7104M8800'                |'TAJ_7343-20_H122_EOL'| '100UF'  | '25V'         | '20%'       | 'DISCRETE' | 'CAP CHIP 100U 25V(20%,SPCAP,7343)KEM'                 | 'SMT'          | ''          | ''            | '20200310'
 '100UF'  | '25V'   | '20%'       | 'SMLF'      | 'EMPTY'    | 'CH7104M8800'(!)             = 'End of Design' | 'End of Life'      | 'CH7104M8800'                |'TAJ_7343-20_H122_EOL'| '100UF'  | '25V'         | '20%'       | 'IO'       | 'CAP CHIP 100U 25V(20%,SPCAP,7343)KEM'                 | 'SMT'          | ''          | ''            | '20200310'
 '470UF'  | '6.3V'  | '20%'       | 'SMLF'      | 'POSCAP'   | 'CH7471MI806'(!)             = ''              | ''                 | 'CH7471MI806'                |'TAJ_D4XA_H158'| '470UF'  | '6.3V'        | '20%'       | 'DISCRETE' | 'CAPCHIP470U 6.3V(20%,POSCAP(TAN)7343)SAY'             | 'SMT'          | ''          | ''            | '20200311'
 '470UF'  | '6.3V'  | '20%'       | 'SMLF'      | 'EMPTY'    | 'CH7471MI806'(!)             = ''              | ''                 | 'CH7471MI806'                |'TAJ_D4XA_H158'| '470UF'  | '6.3V'        | '20%'       | 'IO'       | 'CAPCHIP470U 6.3V(20%,POSCAP(TAN)7343)SAY'             | 'SMT'          | ''          | ''            | '20200311'
 '270UF'  | '25V'   | '20%'       | 'SMLF'      | 'OSCON'    | 'CC72704MZ02'(!)             = ''              | ''                 | 'CC72704MZ02'                |'EC122_315_473S'| '270UF'  | '25V'         | '20%'       | 'DISCRETE' | 'CAP OSCON SMD 270U 25V(20%,125C,8*12)LLN'             | 'SMT'          | ''          | ''            | '20200311'
 '270UF'  | '25V'   | '20%'       | 'SMLF'      | 'EMPTY'    | 'CC72704MZ02'(!)             = ''              | ''                 | 'CC72704MZ02'                |'EC122_315_473S'| '270UF'  | '25V'         | '20%'       | 'IO'       | 'CAP OSCON SMD 270U 25V(20%,125C,8*12)LLN'             | 'SMT'          | ''          | ''            | '20200311'
 '560UF'  | '2V'    | '20%'       | 'SMLF'      | 'SPCAP'    | 'CH756RM8806'(!)             = ''              | ''                 | 'CH756RM8806'                |'TAJ_SX'| '560UF'  | '2V'          | '20%'       | 'DISCRETE' | 'CAPCHIP560U2V(20%,SPCAP,,ESR4.5,7343)MAT'             | 'SMT'          | ''          | ''            | '20200318'
 '560UF'  | '2V'    | '20%'       | 'SMLF'      | 'EMPTY'    | 'CH756RM8806'(!)             = ''              | ''                 | 'CH756RM8806'                |'TAJ_SX'| '560UF'  | '2V'          | '20%'       | 'IO'       | 'CAPCHIP560U2V(20%,SPCAP,,ESR4.5,7343)MAT'             | 'SMT'          | ''          | ''            | '20200318'
 '470UF'  | '2.5V'  | '20%'       | 'SMLF'      | 'SPCAP'    | 'CH747LM8818'(!)             = ''              | ''                 | 'CH747LM8818'                |'TAJ_DXC'| '470UF'  | '2.5V'        | '20%'       | 'DISCRETE' | 'CAP CHIP 470U 2.5V(+-20%,7343,SPCAP)MAT'              | 'SMT'          | ''          | ''            | '20200318'
 '470UF'  | '2.5V'  | '20%'       | 'SMLF'      | 'EMPTY'    | 'CH747LM8818'(!)             = ''              | ''                 | 'CH747LM8818'                |'TAJ_DXC'| '470UF'  | '2.5V'        | '20%'       | 'IO'       | 'CAP CHIP 470U 2.5V(+-20%,7343,SPCAP)MAT'              | 'SMT'          | ''          | ''            | '20200318'
 '330UF'  | '2.5V'  | '+10/-35%'  | 'SMLF'      | 'SPCAP'    | 'CH733LY8802'(!)             = ''              | ''                 | 'CH733LY8802'                |'TAJ_SX'| '330UF'  | '2.5V'        | '+10/-35%'  | 'DISCRETE' | 'CAPCHIP 330U 2.5V(10/-35%,SPCAP,7343)MAT'             | 'SMT'          | ''          | ''            | '20200326'
 '330UF'  | '2.5V'  | '+10/-35%'  | 'SMLF'      | 'EMPTY'    | 'CH733LY8802'(!)             = ''              | ''                 | 'CH733LY8802'                |'TAJ_SX'| '330UF'  | '2.5V'        | '+10/-35%'  | 'IO'       | 'CAPCHIP 330U 2.5V(10/-35%,SPCAP,7343)MAT'             | 'SMT'          | ''          | ''            | '20200326'
 '330UF'  | '10V'   | '20%'       | 'SMLF'      | 'TANT'     | 'CH7332MI800'(!)             = ''              | ''                 | 'CH7332MI800'                |'TAJ_7343-20_H170'| '330UF'  | '10V'         | '20%'       | 'DISCRETE' | 'CAPCHIP330U 10V(20%,POSCAP(TAN),7343)KEM'             | 'SMT'          | ''          | ''            | '20200407'
 '330UF'  | '10V'   | '20%'       | 'SMLF'      | 'EMPTY'    | 'CH7332MI800'(!)             = ''              | ''                 | 'CH7332MI800'                |'TAJ_7343-20_H170'| '330UF'  | '10V'         | '20%'       | 'IO'       | 'CAPCHIP330U 10V(20%,POSCAP(TAN),7343)KEM'             | 'SMT'          | ''          | ''            | '20200407'
 '330UF'  | '10V'   | '20%'       | 'SMLF'      | 'POSCAP'   | 'CH7332MI801'(!)             = ''              | ''                 | 'CH7332MI801'                |'TAJ_D4XB'| '330UF'  | '10V'         | '20%'       | 'DISCRETE' | 'CAPCHIP330U 10V(20%,POSCAP(TAN),7343)SAY'             | 'SMT'          | ''          | ''            | '20200406'
 '330UF'  | '10V'   | '20%'       | 'SMLF'      | 'EMPTY'    | 'CH7332MI801'(!)             = ''              | ''                 | 'CH7332MI801'                |'TAJ_D4XB'| '330UF'  | '10V'         | '20%'       | 'IO'       | 'CAPCHIP330U 10V(20%,POSCAP(TAN),7343)SAY'             | 'SMT'          | ''          | ''            | '20200406'
 '330UF'  | '10V'   | '20%'       | 'SMLF'      | 'POSCAP'   | 'CH7332M8804'(!)             = 'End of Design' | 'Comp-Approve'     | 'CH7332M8804'                |'TAJ_D4XB'| '330UF'  | '10V'         | '20%'       | 'DISCRETE' | 'CAP CHIP 330U 10V(20%,ESR25,7343,H4.0)'               | 'SMT'          | ''          | ''            | '20200406'
 '330UF'  | '10V'   | '20%'       | 'SMLF'      | 'EMPTY'    | 'CH7332M8804'(!)             = 'End of Design' | 'Comp-Approve'     | 'CH7332M8804'                |'TAJ_D4XB'| '330UF'  | '10V'         | '20%'       | 'IO'       | 'CAP CHIP 330U 10V(20%,ESR25,7343,H4.0)'               | 'SMT'          | ''          | ''            | '20200406'
 '270UF'  | '16V'   | '20%'       | 'THLF'      | 'OSCON'    | 'CC72703MD33'(!)             = ''              | ''                 | 'CC72703MD33'                |'EC2-5_6-8_9'| '270UF'  | '16V'         | '20%'       | 'DISCRETE' | 'CAP OSCON DIP 270U 16V(20%,,6.3*9)APQ'                | 'DIP'          | ''          | ''            | '20200416'
 '270UF'  | '16V'   | '20%'       | 'THLF'      | 'EMPTY'    | 'CC72703MD33'(!)             = ''              | ''                 | 'CC72703MD33'                |'EC2-5_6-8_9'| '270UF'  | '16V'         | '20%'       | 'IO'       | 'CAP OSCON DIP 270U 16V(20%,,6.3*9)APQ'                | 'DIP'          | ''          | ''            | '20200416'
 '560UF'  | '6.3V'  | '20%'       | 'THLF'      | 'OSCON'    | 'CC75601MD18'(!)             = ''              | ''                 | 'CC75601MD18'                |'EC2-5_6-8_9'| '560UF'  | '6.3V'        | '20%'       | 'DISCRETE' | 'CAP OSCON DIP 560U 6.3V(+-20%,6.3*9)APQ'              | 'DIP'          | ''          | ''            | '20200417'
 '560UF'  | '6.3V'  | '20%'       | 'THLF'      | 'EMPTY'    | 'CC75601MD18'(!)             = ''              | ''                 | 'CC75601MD18'                |'EC2-5_6-8_9'| '560UF'  | '6.3V'        | '20%'       | 'IO'       | 'CAP OSCON DIP 560U 6.3V(+-20%,6.3*9)APQ'              | 'DIP'          | ''          | ''            | '20200417'
 '560UF'  | '2.5V'  | '20%'       | 'THLF'      | 'OSCON'    | 'CC7560JMD18'(!)             = ''              | ''                 | 'CC7560JMD18'                |'EC2_5-5_9XA'| '560UF'  | '2.5V'        | '20%'       | 'DISCRETE' | 'CAP OSCON DIP 560U 2.5V(+-20%,5*9)APQ'                | 'DIP'          | ''          | ''            | '20200416'
 '560UF'  | '2.5V'  | '20%'       | 'THLF'      | 'EMPTY'    | 'CC7560JMD18'(!)             = ''              | ''                 | 'CC7560JMD18'                |'EC2_5-5_9XA'| '560UF'  | '2.5V'        | '20%'       | 'IO'       | 'CAP OSCON DIP 560U 2.5V(+-20%,5*9)APQ'                | 'DIP'          | ''          | ''            | '20200416'
 '100UF'  | '16V'   | '20%'       | 'SMLF'      | 'OSCON'    | 'CC71003MZ32'(!)             = ''              | ''                 | 'CC71003MZ32'                |'EC56_197_229S'| '100UF'  | '16V'         | '20%'       | 'DISCRETE' | 'CAP OSCON SMD 100U 16V(20%,5*5.8)APQ'                 | 'SMT'          | ''          | ''            | '20200715'
 '100UF'  | '16V'   | '20%'       | 'SMLF'      | 'EMPTY'    | 'CC71003MZ32'(!)             = ''              | ''                 | 'CC71003MZ32'                |'EC56_197_229S'| '100UF'  | '16V'         | '20%'       | 'IO'       | 'CAP OSCON SMD 100U 16V(20%,5*5.8)APQ'                 | 'SMT'          | ''          | ''            | '20200715'
 '2200UF' | '16V'   | '20%'       | 'THLF'      | 'OSCON'    | 'SP_CC82203MD07'(!)          = ''              | ''                 | 'CC82203MD07'                |'G_EC5_10-5_21-5XA'| '2200UF' | '16V'         | '20%'       | 'DISCRETE' | 'CAP OSCON DIP 2200U 16V(20%,10*20)NPN_FOR SEL'        | 'DIP'          | ''          | ''            | '20200731'
 '2200UF' | '16V'   | '20%'       | 'THLF'      | 'EMPTY'    | 'SP_CC82203MD07'(!)          = ''              | ''                 | 'CC82203MD07'                |'G_EC5_10-5_21-5XA'| '2200UF' | '16V'         | '20%'       | 'IO'       | 'CAP OSCON DIP 2200U 16V(20%,10*20)NPN_FOR SEL'        | 'DIP'          | ''          | ''            | '20200731'
 '330UF'  | '10V'   | '20%'       | 'SMLF'      | 'POSCAP'   | 'CH7332M8800'(!)             = 'End of Design' | 'Comp-Approve'     | 'CH7332M8800'                |'TAJ_7343-20_H170'| '330UF'  | '10V'         | '20%'       | 'DISCRETE' | 'CAP CHIP 330U 10V(20%,ESR6,7343,H4.0)'                | 'SMT'          | ''          | ''            | '20200917'
 '330UF'  | '10V'   | '20%'       | 'SMLF'      | 'EMPTY'    | 'CH7332M8800'(!)             = 'End of Design' | 'Comp-Approve'     | 'CH7332M8800'                |'TAJ_7343-20_H170'| '330UF'  | '10V'         | '20%'       | 'IO'       | 'CAP CHIP 330U 10V(20%,ESR6,7343,H4.0)'                | 'SMT'          | ''          | ''            | '20200917'
 '100UF'  | '10V'   | '20%'       | 'SMLF'      | 'POSCAP'   | 'CH7102M8808'(!)             = 'End of Design' | 'Comp-Approve'     | 'CH7102M8808'                |'TAJ_7343-20'| '100UF'  | '10V'         | '20%'       | 'DISCRETE' | 'CAP CHIP 100U 10V(20%,ESR45,7343,H1.9)'               | 'SMT'          | ''          | ''            | '20200922'
 '100UF'  | '10V'   | '20%'       | 'SMLF'      | 'EMPTY'    | 'CH7102M8808'(!)             = 'End of Design' | 'Comp-Approve'     | 'CH7102M8808'                |'TAJ_7343-20'| '100UF'  | '10V'         | '20%'       | 'IO'       | 'CAP CHIP 100U 10V(20%,ESR45,7343,H1.9)'               | 'SMT'          | ''          | ''            | '20200922'
 '330UF'  | '6.3V'  | '20%'       | 'SMLF'      | 'OSCON'    | 'CC73301MZ19'(!)             = ''              | ''                 | 'CC73301MZ19'                |'EC75_248_229SXA'| '330UF'  | '6.3V'        | '20%'       | 'DISCRETE' | 'CAP OSCON SMD 330U 6.3V(20%,6.3*5.8)NPN'              | 'SMT'          | ''          | ''            | '20201105'
 '330UF'  | '6.3V'  | '20%'       | 'SMLF'      | 'EMPTY'    | 'CC73301MZ19'(!)             = ''              | ''                 | 'CC73301MZ19'                |'EC75_248_229SXA'| '330UF'  | '6.3V'        | '20%'       | 'IO'       | 'CAP OSCON SMD 330U 6.3V(20%,6.3*5.8)NPN'              | 'SMT'          | ''          | ''            | '20201105'
 '470UF'  | '2.5V'  | '20%'       | 'SMLF'      | 'SPCAP'    | 'CH747LM8825'(!)             = ''              | ''                 | 'CH747LM8825'                |'TAJ_SX'| '470UF'  | '2.5V'        | '20%'       | 'DISCRETE' | 'CAPCHIP 470U 2.5V(20%,SP,ESR4.5,7343)MAT'             | 'SMT'          | ''          | ''            | '20201120'
 '470UF'  | '2.5V'  | '20%'       | 'SMLF'      | 'EMPTY'    | 'CH747LM8825'(!)             = ''              | ''                 | 'CH747LM8825'                |'TAJ_SX'| '470UF'  | '2.5V'        | '20%'       | 'IO'       | 'CAPCHIP 470U 2.5V(20%,SP,ESR4.5,7343)MAT'             | 'SMT'          | ''          | ''            | '20201120'
 '220UF'  | '6.3V'  | '+10/-35%'  | 'SMLF'      | 'SPCAP'    | 'CH7221Y8801'(!)             = ''              | ''                 | 'CH7221Y8801'                |'TAJ_DXC'| '220UF'  | '6.3V'        | '+10/-35%'  | 'DISCRETE' | 'CAP CHIP 220U 6.3V(+10/-35%,7343,SP)MAT'              | 'SMT'          | ''          | ''            | '20201203'
 '220UF'  | '6.3V'  | '+10/-35%'  | 'SMLF'      | 'EMPTY'    | 'CH7221Y8801'(!)             = ''              | ''                 | 'CH7221Y8801'                |'TAJ_DXC'| '220UF'  | '6.3V'        | '+10/-35%'  | 'IO'       | 'CAP CHIP 220U 6.3V(+10/-35%,7343,SP)MAT'              | 'SMT'          | ''          | ''            | '20201203'
 '220UF'  | '6.3V'  | '20%'       | 'SMLF'      | 'SPCAP'    | 'CH7221M8816'(!)             = ''              | ''                 | 'CH7221M8816'                |'TAJ_DXC'| '220UF'  | '6.3V'        | '20%'       | 'DISCRETE' | 'CAP CHIP 220U 6.3V(20%,SP,ESR15,7343)MAT'             | 'SMT'          | ''          | ''            | '20201203'
 '220UF'  | '6.3V'  | '20%'       | 'SMLF'      | 'EMPTY'    | 'CH7221M8816'(!)             = ''              | ''                 | 'CH7221M8816'                |'TAJ_DXC'| '220UF'  | '6.3V'        | '20%'       | 'IO'       | 'CAP CHIP 220U 6.3V(20%,SP,ESR15,7343)MAT'             | 'SMT'          | ''          | ''            | '20201203'
 '220UF'  | '6.3V'  | '20%'       | 'SMLF'      | 'POSCAP'   | 'CH7221MI804'(!)             = ''              | ''                 | 'CH7221MI804'                |'TAJ_D2EXA'| '220UF'  | '6.3V'        | '20%'       | 'DISCRETE' | 'CAPCHIP 220U 6.3V(20%,POS,ESR18,7343)SAY'             | 'SMT'          | ''          | ''            | '20201203'
 '220UF'  | '6.3V'  | '20%'       | 'SMLF'      | 'EMPTY'    | 'CH7221MI804'(!)             = ''              | ''                 | 'CH7221MI804'                |'TAJ_D2EXA'| '220UF'  | '6.3V'        | '20%'       | 'IO'       | 'CAPCHIP 220U 6.3V(20%,POS,ESR18,7343)SAY'             | 'SMT'          | ''          | ''            | '20201203'
 '390UF'  | '2.5V'  | '20%'       | 'SMLF'      | 'OSCON'    | 'CC7390JMZ12'(!)             = ''              | ''                 | 'CC7390JMZ12'                |'EC56_197_229SXA'| '390UF'  | '2.5V'        | '20%'       | 'DISCRETE' | 'CAP OSCON 390U 2.5V(20%,105C,5*5.8)APQ'               | 'SMT'          | ''          | ''            | '20201209'
 '390UF'  | '2.5V'  | '20%'       | 'SMLF'      | 'EMPTY'    | 'CC7390JMZ12'(!)             = ''              | ''                 | 'CC7390JMZ12'                |'EC56_197_229SXA'| '390UF'  | '2.5V'        | '20%'       | 'IO'       | 'CAP OSCON 390U 2.5V(20%,105C,5*5.8)APQ'               | 'SMT'          | ''          | ''            | '20201209'
 '220UF'  | '6.3V'  | '20%'       | 'SMLF'      | 'OSCON'    | 'CC72201MZ39'(!)             = ''              | ''                 | 'CC72201MZ39'                |'EC56_197_229SXA'| '220UF'  | '6.3V'        | '20%'       | 'DISCRETE' | 'CAP OSCON SMD 220U 6.3V(20%,5*5.8)APQ'                | 'SMT'          | ''          | ''            | '20201209'
 '220UF'  | '6.3V'  | '20%'       | 'SMLF'      | 'EMPTY'    | 'CC72201MZ39'(!)             = ''              | ''                 | 'CC72201MZ39'                |'EC56_197_229SXA'| '220UF'  | '6.3V'        | '20%'       | 'IO'       | 'CAP OSCON SMD 220U 6.3V(20%,5*5.8)APQ'                | 'SMT'          | ''          | ''            | '20201209'
 '270UF'  | '16V'   | '20%'       | 'SMLF'      | 'OSCON'    | 'CC72703MZ11'(!)             = ''              | ''                 | 'CC72703MZ11'                |'EC75_248_304S'| '270UF'  | '16V'         | '20%'       | 'DISCRETE' | 'CAP OSCON SMD 270U 16V(20%,6.3*7.7)NPN'               | 'SMT'          | ''          | ''            | '20201209'
 '270UF'  | '16V'   | '20%'       | 'SMLF'      | 'EMPTY'    | 'CC72703MZ11'(!)             = ''              | ''                 | 'CC72703MZ11'                |'EC75_248_304S'| '270UF'  | '16V'         | '20%'       | 'IO'       | 'CAP OSCON SMD 270U 16V(20%,6.3*7.7)NPN'               | 'SMT'          | ''          | ''            | '20201209'
 '270UF'  | '16V'   | '20%'       | 'SMLF'      | 'OSCON'    | 'CC72703MZ15'(!)             = ''              | ''                 | 'CC72703MZ15'                |'EC83_248_296S'| '270UF'  | '16V'         | '20%'       | 'DISCRETE' | 'CAP OSCON SMD 270U 16V(20%,6.3*7.5)APQ'               | 'SMT'          | ''          | ''            | '20201209'
 '270UF'  | '16V'   | '20%'       | 'SMLF'      | 'EMPTY'    | 'CC72703MZ15'(!)             = ''              | ''                 | 'CC72703MZ15'                |'EC83_248_296S'| '270UF'  | '16V'         | '20%'       | 'IO'       | 'CAP OSCON SMD 270U 16V(20%,6.3*7.5)APQ'               | 'SMT'          | ''          | ''            | '20201209'
 '68UF'   | '16V'   | '20%'       | 'SMLF'      | 'POSCAP'   | 'CH6683MI802'(!)             = ''              | 'P/N Release'      | 'CH6683MI802'                | 'TAJ_DXD_H79'              | '68UF'   | '16V'         | '20%'       | 'DISCRETE' | 'CAP CHIP 68U 16V(20%,ESR=50,7343,POS)NEC'             | 'SMT'          | ''          | ''            | '20201222'
 '68UF'   | '16V'   | '20%'       | 'SMLF'      | 'EMPTY'    | 'CH6683MI802'(!)             = ''              | 'P/N Release'      | 'CH6683MI802'                | 'TAJ_DXD_H79'              | '68UF'   | '16V'         | '20%'       | 'IO'       | 'CAP CHIP 68U 16V(20%,ESR=50,7343,POS)NEC'             | 'SMT'          | ''          | ''            | '20201222'
 '68UF'   | '16V'   | '20%'       | 'SMLF'      | 'POSCAP'   | 'CH6683MI804'(!)             = ''              | ''                 | 'CH6683MI804'                |'TAJ_V'| '68UF'   | '16V'         | '20%'       | 'DISCRETE' | 'CAP CHIP 68U 16V(20%,ESR50,7343,POS)KEM'              | 'SMT'          | ''          | ''            | '20201222'
 '68UF'   | '16V'   | '20%'       | 'SMLF'      | 'EMPTY'    | 'CH6683MI804'(!)             = ''              | ''                 | 'CH6683MI804'                |'TAJ_V'| '68UF'   | '16V'         | '20%'       | 'IO'       | 'CAP CHIP 68U 16V(20%,ESR50,7343,POS)KEM'              | 'SMT'          | ''          | ''            | '20201222'
 '68UF'   | '16V'   | '20%'       | 'SMLF'      | 'POSCAP'   | 'CH6683MI801'(!)             = ''              | 'P/N Release'      | 'CH6683MI801'                | 'TAJ_D2EXA_H79'            | '68UF'   | '16V'         | '20%'       | 'DISCRETE' | 'CAP CHIP 68U 16V(20%,ESR=50,7343,POS)SAY'             | 'SMT'          | ''          | ''            | '20201222'
 '68UF'   | '16V'   | '20%'       | 'SMLF'      | 'EMPTY'    | 'CH6683MI801'(!)             = ''              | 'P/N Release'      | 'CH6683MI801'                | 'TAJ_D2EXA_H79'            | '68UF'   | '16V'         | '20%'       | 'IO'       | 'CAP CHIP 68U 16V(20%,ESR=50,7343,POS)SAY'             | 'SMT'          | ''          | ''            | '20201222'
 '1000UF' | '63V'   | '20%'       | 'SMLF'      | 'ALUM'     | 'CC81007MZ00'(!)             = ''              | ''                 | 'CC81007MZ00'                |'EC264_709_847S'| '1000UF' | '63V'         | '20%'       | 'DISCRETE' | 'CAP ELEC SMD 1000U 63V(20%,18*21.5)'                  | 'SMT'          | ''          | ''            | '20201231'
 '1000UF' | '63V'   | '20%'       | 'SMLF'      | 'EMPTY'    | 'CC81007MZ00'(!)             = ''              | ''                 | 'CC81007MZ00'                |'EC264_709_847S'| '1000UF' | '63V'         | '20%'       | 'IO'       | 'CAP ELEC SMD 1000U 63V(20%,18*21.5)'                  | 'SMT'          | ''          | ''            | '20201231'
 '100UF'  | '16V'   | '20%'       | 'THLF'      | 'ALUM'     | 'SP_CC71003MD17_1'(!)        = ''              | ''                 | 'CC71003MD17'                |'G_EC2-5_6-8_6'| '100UF'  | '16V'         | '20%'       | 'DISCRETE' | 'CAP OSCON DIP 100U 16V(20%,6.3*6)NPN_FOR SEL'         | 'DIP'          | ''          | ''            | '20210118'
 '100UF'  | '16V'   | '20%'       | 'THLF'      | 'EMPTY'    | 'SP_CC71003MD17_1'(!)        = ''              | ''                 | 'CC71003MD17'                |'G_EC2-5_6-8_6'| '100UF'  | '16V'         | '20%'       | 'IO'       | 'CAP OSCON DIP 100U 16V(20%,6.3*6)NPN_FOR SEL'         | 'DIP'          | ''          | ''            | '20210118'
 '470UF'  | '2.5V'  | '20%'       | 'SMLF'      | 'SPCAP'    | 'CH747LM8823'(!)             = ''              | ''                 | 'CH747LM8823'                |'TAJ_7343-20_H83'| '470UF'  | '2.5V'        | '20%'       | 'DISCRETE' | 'CAP CHIP 470U 2.5V(+-20%,7343,SPCAP)KEM'              | 'SMT'          | ''          | ''            | '20210126'
 '470UF'  | '2.5V'  | '20%'       | 'SMLF'      | 'EMPTY'    | 'CH747LM8823'(!)             = ''              | ''                 | 'CH747LM8823'                |'TAJ_7343-20_H83'| '470UF'  | '2.5V'        | '20%'       | 'IO'       | 'CAP CHIP 470U 2.5V(+-20%,7343,SPCAP)KEM'              | 'SMT'          | ''          | ''            | '20210126'
 '470UF'  | '2.5V'  | '20%'       | 'SMLF'      | 'SPCAP'    | 'CH747LM8822'(!)             = ''              | ''                 | 'CH747LM8822'                |'TAJ_7343-20_H83'| '470UF'  | '2.5V'        | '20%'       | 'DISCRETE' | 'CAPCHIP 470U 2.5V(20%,SP,ESR4.5,7343)KEM'             | 'SMT'          | ''          | ''            | '20210126'
 '470UF'  | '2.5V'  | '20%'       | 'SMLF'      | 'EMPTY'    | 'CH747LM8822'(!)             = ''              | ''                 | 'CH747LM8822'                |'TAJ_7343-20_H83'| '470UF'  | '2.5V'        | '20%'       | 'IO'       | 'CAPCHIP 470U 2.5V(20%,SP,ESR4.5,7343)KEM'             | 'SMT'          | ''          | ''            | '20210126'
 '330UF'  | '2V'    | '+10-35%'   | 'SMLF'      | 'SPCAP'    | 'CH733RY8808'(!)             = ''              | ''                 | 'CH733RY8808'                |'TAJ_S'| '330UF'  | '2V'          | '+10-35%'   | 'DISCRETE' | 'CAP CHIP 330U 2V(+10-35%SPCAP7343)APQ'                | 'SMT'          | ''          | ''            | '20210127'
 '330UF'  | '2V'    | '+10-35%'   | 'SMLF'      | 'EMPTY'    | 'CH733RY8808'(!)             = ''              | ''                 | 'CH733RY8808'                |'TAJ_S'| '330UF'  | '2V'          | '+10-35%'   | 'IO'       | 'CAP CHIP 330U 2V(+10-35%SPCAP7343)APQ'                | 'SMT'          | ''          | ''            | '20210127'
 '680UF'  | '35V'   | '20%'       | 'SMLF'      | 'ALUM'     | 'CC76805MZ01'(!)             = ''              | ''                 | 'CC76805MZ01'                |'EC178_394_394SXA_H414'| '680UF'  | '35V'         | '20%'       | 'DISCRETE' | 'CAP ELEC SMD 680U 35V(20%,10*10)NPN'                  | 'SMT'          | ''          | ''            | '20210323'
 '680UF'  | '35V'   | '20%'       | 'SMLF'      | 'EMPTY'    | 'CC76805MZ01'(!)             = ''              | ''                 | 'CC76805MZ01'                |'EC178_394_394SXA_H414'| '680UF'  | '35V'         | '20%'       | 'IO'       | 'CAP ELEC SMD 680U 35V(20%,10*10)NPN'                  | 'SMT'          | ''          | ''            | '20210323'
 '2200UF' | '35V'   | '20%'       | 'SMLF'      | 'ALUM'     | 'CC82205MZ01'(!)             = ''              | ''                 | 'CC82205MZ01'                |'EC256_709_847S'| '2200UF' | '35V'         | '20%'       | 'DISCRETE' | 'CAP ELEC SMD 2200U 35V(20%,18*21.5)NPN'               | 'SMT'          | ''          | ''            | '20210323'
 '2200UF' | '35V'   | '20%'       | 'SMLF'      | 'EMPTY'    | 'CC82205MZ01'(!)             = ''              | ''                 | 'CC82205MZ01'                |'EC256_709_847S'| '2200UF' | '35V'         | '20%'       | 'IO'       | 'CAP ELEC SMD 2200U 35V(20%,18*21.5)NPN'               | 'SMT'          | ''          | ''            | '20210323'
 '330UF'  | '2.5V'  | '+10%~-35%' | 'SMLF'      | 'SPCAP'    | 'CH733LY8800'(!)             = ''              | ''                 | 'CH733LY8800'                | 'TAJ_DXD_H79'              | '330UF'  | '2.5V'        | '+10%~-35%' | 'DISCRETE' | 'CAP 330U 2.5V(+10%~-35%,SPCAP,ESR=9,7343'             | 'SMT'          | ''          | ''            | '20210427'
 '330UF'  | '2.5V'  | '+10%~-35%' | 'SMLF'      | 'EMPTY'    | 'CH733LY8800'(!)             = ''              | ''                 | 'CH733LY8800'                | 'TAJ_DXD_H79'              | '330UF'  | '2.5V'        | '+10%~-35%' | 'IO'       | 'CAP 330U 2.5V(+10%~-35%,SPCAP,ESR=9,7343'             | 'SMT'          | ''          | ''            | '20210427'
 '56UF'   | '80V'   | '20%'       | 'SMLF'      | 'ALUM'     | 'CC6560EMZ00'(!)             = ''              | ''                 | 'CC6560EMZ00'                |'EC178_394_394SXA_H414'| '56UF'   | '80V'         | '20%'       | 'DISCRETE' | 'CAP ELEC SMD 56UF 80V(20%,ESR33,10*10)'               | 'SMT'          | ''          | ''            | '20210503'
 '56UF'   | '80V'   | '20%'       | 'SMLF'      | 'EMPTY'    | 'CC6560EMZ00'(!)             = ''              | ''                 | 'CC6560EMZ00'                |'EC178_394_394SXA_H414'| '56UF'   | '80V'         | '20%'       | 'IO'       | 'CAP ELEC SMD 56UF 80V(20%,ESR33,10*10)'               | 'SMT'          | ''          | ''            | '20210503'
 '1000UF' | '100V'  | '20%'       | 'THLF'      | 'ALUM'     | 'CC81008MD01'(!)             = ''              | ''                 | 'CC81008MD01'                |'EC296_709_1398'| '1000UF' | '100V'        | '20%'       | 'DISCRETE' | 'CAPELECDIP 1000U100V(20%,18*35.5)MAT AEC'             | 'DIP'          | ''          | ''            | '20210504'
 '1000UF' | '100V'  | '20%'       | 'THLF'      | 'EMPTY'    | 'CC81008MD01'(!)             = ''              | ''                 | 'CC81008MD01'                |'EC296_709_1398'| '1000UF' | '100V'        | '20%'       | 'IO'       | 'CAPELECDIP 1000U100V(20%,18*35.5)MAT AEC'             | 'DIP'          | ''          | ''            | '20210504'
 '560UF'  | '2.5V'  | '20%'       | 'THLF'      | 'OSCON'    | 'CC7560JMD17'(!)             = ''              | ''                 | 'CC7560JMD17'                |'EC78_197_315XB'| '560UF'  | '2.5V'        | '20%'       | 'DISCRETE' | 'CAP OSCON DIP 560U 2.5V(20%,ESR7,5*8)TOW'             | 'DIP'          | ''          | ''            | '20210506'
 '560UF'  | '2.5V'  | '20%'       | 'THLF'      | 'EMPTY'    | 'CC7560JMD17'(!)             = ''              | ''                 | 'CC7560JMD17'                |'EC78_197_315XB'| '560UF'  | '2.5V'        | '20%'       | 'IO'       | 'CAP OSCON DIP 560U 2.5V(20%,ESR7,5*8)TOW'             | 'DIP'          | ''          | ''            | '20210506'
 '100UF'  | '16V'   | '20%'       | 'SMLF'      | 'ALUM'     | 'CC71003MZ37'(!)             = ''              | ''                 | 'CC71003MZ37'                |'EC56_197_229SXA'| '100UF'  | '16V'         | '20%'       | 'DISCRETE' | 'CAP OS SMD 100U 16V(20%,ESR27,5*5.7)TOW'              | 'SMT'          | ''          | ''            | '20210510'
 '100UF'  | '16V'   | '20%'       | 'SMLF'      | 'EMPTY'    | 'CC71003MZ37'(!)             = ''              | ''                 | 'CC71003MZ37'                |'EC56_197_229SXA'| '100UF'  | '16V'         | '20%'       | 'IO'       | 'CAP OS SMD 100U 16V(20%,ESR27,5*5.7)TOW'              | 'SMT'          | ''          | ''            | '20210510'
 '1500UF' | '4V'    | '20%'       | 'SMLF'      | 'OSCON'    | 'CC8150IMZ00'(!)             = ''              | ''                 | 'CC8150IMZ00'                |'EC181_394_390S'| '1500UF' | '4V'          | '20%'       | 'DISCRETE' | 'CAP OSCON SMD 1500UF 4V(20%,105C,10*10)'              | 'SMT'          | ''          | ''            | '20210512'
 '1500UF' | '4V'    | '20%'       | 'SMLF'      | 'EMPTY'    | 'CC8150IMZ00'(!)             = ''              | ''                 | 'CC8150IMZ00'                |'EC181_394_390S'| '1500UF' | '4V'          | '20%'       | 'IO'       | 'CAP OSCON SMD 1500UF 4V(20%,105C,10*10)'              | 'SMT'          | ''          | ''            | '20210512'
 '2200UF' | '80V'   | '20%'       | 'THLF'      | 'ALUM'     | 'CC8220EMD00'(!)             = ''              | ''                 | 'CC8220EMD00'                |'EC394_866_1772'| '2200UF' | '80V'         | '20%'       | 'DISCRETE' | 'CAP ELEC DIP 2200UF 80V(+-20%,22*45)'                 | 'DIP'          | ''          | ''            | '20210512'
 '2200UF' | '80V'   | '20%'       | 'THLF'      | 'EMPTY'    | 'CC8220EMD00'(!)             = ''              | ''                 | 'CC8220EMD00'                |'EC394_866_1772'| '2200UF' | '80V'         | '20%'       | 'IO'       | 'CAP ELEC DIP 2200UF 80V(+-20%,22*45)'                 | 'DIP'          | ''          | ''            | '20210512'
 '680UF'  | '80V'   | '20%'       | 'SMLF'      | 'ALUM'     | 'CC7680EMZ00'(!)             = ''              | ''                 | 'CC7680EMZ00'                |'EC256_709_847S'| '680UF'  | '80V'         | '20%'       | 'DISCRETE' | 'CAP ELEC SMD 680UF 80V(+-20%,18*21.5)'                | 'SMT'          | ''          | ''            | '20210514'
 '680UF'  | '80V'   | '20%'       | 'SMLF'      | 'EMPTY'    | 'CC7680EMZ00'(!)             = ''              | ''                 | 'CC7680EMZ00'                |'EC256_709_847S'| '680UF'  | '80V'         | '20%'       | 'IO'       | 'CAP ELEC SMD 680UF 80V(+-20%,18*21.5)'                | 'SMT'          | ''          | ''            | '20210514'
 '1000UF' | '2.5V'  | '20%'       | 'SMLF'      | 'POSCAP'   | 'CH810LMI800'(!)             = ''              | ''                 | 'CH810LMI800'                |'TAJ_D4XB'| '1000UF' | '2.5V'        | '20%'       | 'DISCRETE' | 'CAP CHIP 1000U 2.5V(+-20%,POSCAP,7343)'               | 'SMT'          | ''          | ''            | '20210519'
 '1000UF' | '2.5V'  | '20%'       | 'SMLF'      | 'EMPTY'    | 'CH810LMI800'(!)             = ''              | ''                 | 'CH810LMI800'                |'TAJ_D4XB'| '1000UF' | '2.5V'        | '20%'       | 'IO'       | 'CAP CHIP 1000U 2.5V(+-20%,POSCAP,7343)'               | 'SMT'          | ''          | ''            | '20210519'
 '2200UF' | '63V'   | '20%'       | 'THLF'      | 'ALUM'     | 'CC82207MD00'(!)             = ''              | ''                 | 'CC82207MD00'                |'EC296_709_1575'| '2200UF' | '63V'         | '20%'       | 'DISCRETE' | 'CAP ELEC DIP 2200U 63V(20%,18*40)'                    | 'DIP'          | ''          | ''            | '20210520'
 '2200UF' | '63V'   | '20%'       | 'THLF'      | 'EMPTY'    | 'CC82207MD00'(!)             = ''              | ''                 | 'CC82207MD00'                |'EC296_709_1575'| '2200UF' | '63V'         | '20%'       | 'IO'       | 'CAP ELEC DIP 2200U 63V(20%,18*40)'                    | 'DIP'          | ''          | ''            | '20210520'
 '2200UF' | '80V'   | '20%'       | 'THLF'      | 'ALUM'     | 'CC8220EMD01'(!)             = ''              | ''                 | 'CC8220EMD01'                |'EC296_709_1772'| '2200UF' | '80V'         | '20%'       | 'DISCRETE' | 'CAP ELEC DIP 2200UF 80V(+-20%,18*45)'                 | 'DIP'          | ''          | ''            | '20210527'
 '2200UF' | '80V'   | '20%'       | 'THLF'      | 'EMPTY'    | 'CC8220EMD01'(!)             = ''              | ''                 | 'CC8220EMD01'                |'EC296_709_1772'| '2200UF' | '80V'         | '20%'       | 'IO'       | 'CAP ELEC DIP 2200UF 80V(+-20%,18*45)'                 | 'DIP'          | ''          | ''            | '20210527'
 '2200UF' | '35V'   | '20%'       | 'SMLF'      | 'ALUM'     | 'CC82205MZ02'(!)             = ''              | ''                 | 'CC82205MZ02'                |'EC264_709_650S_H670'| '2200UF' | '35V'         | '20%'       | 'DISCRETE' | 'CAP ELEC SMD 2200UF 35V(20%,18*16.5)MAT'              | 'SMT'          | ''          | ''            | '20210601'
 '2200UF' | '35V'   | '20%'       | 'SMLF'      | 'EMPTY'    | 'CC82205MZ02'(!)             = ''              | ''                 | 'CC82205MZ02'                |'EC264_709_650S_H670'| '2200UF' | '35V'         | '20%'       | 'IO'       | 'CAP ELEC SMD 2200UF 35V(20%,18*16.5)MAT'              | 'SMT'          | ''          | ''            | '20210601'
 '100UF'  | '100V'  | '20%'       | 'THLF'      | 'ALUM'     | 'CC71008MD07'(!)             = ''              | ''                 | 'CC71008MD07'                |'EC5_10-5_21-5'| '100UF'  | '100V'        | '20%'       | 'DISCRETE' | 'CAP ELEC DIP 100U 100V(20%,10*20)NPN'                 | 'DIP'          | ''          | ''            | '20210622'
 '100UF'  | '100V'  | '20%'       | 'THLF'      | 'EMPTY'    | 'CC71008MD07'(!)             = ''              | ''                 | 'CC71008MD07'                |'EC5_10-5_21-5'| '100UF'  | '100V'        | '20%'       | 'IO'       | 'CAP ELEC DIP 100U 100V(20%,10*20)NPN'                 | 'DIP'          | ''          | ''            | '20210622'
 '3.3F'   | '3V'    | '-10/30%'   | 'THLF'      | ''         | 'CCB330KTD00'(!)             = ''              | ''                 | 'CCB330KTD00'                |'EC3-5_8-5_21'| '3.3F'   | '3V'          | '-10/30%'   | 'DISCRETE' | 'CAPELEC DIP 3.3F 3V(-10/30%,8.5*21)SUPER'             | 'DIP'          | ''          | ''            | '20210708'
 '3.3F'   | '3V'    | '-10/30%'   | 'THLF'      | 'EMPTY'    | 'CCB330KTD00'(!)             = ''              | ''                 | 'CCB330KTD00'                |'EC3-5_8-5_21'| '3.3F'   | '3V'          | '-10/30%'   | 'IO'       | 'CAPELEC DIP 3.3F 3V(-10/30%,8.5*21)SUPER'             | 'DIP'          | ''          | ''            | '20210708'
 '100UF'  | '100V'  | '20%'       | 'THLF'      | 'ALUM'     | 'CC71008MD10'(!)             = ''              | ''                 | 'CC71008MD10'                |'EC197_394_787XC_H867'| '100UF'  | '100V'        | '20%'       | 'DISCRETE' | 'CAP ELEC DIP 100U 100V(20%,10*20)NIC'                 | 'DIP'          | ''          | ''            | '20210726'
 '100UF'  | '100V'  | '20%'       | 'THLF'      | 'EMPTY'    | 'CC71008MD10'(!)             = ''              | ''                 | 'CC71008MD10'                |'EC197_394_787XC_H867'| '100UF'  | '100V'        | '20%'       | 'IO'       | 'CAP ELEC DIP 100U 100V(20%,10*20)NIC'                 | 'DIP'          | ''          | ''            | '20210726'
 '1800UF' | '80V'   | '20%'       | 'THLF'      | 'ALUM'     | 'CC8180EMD00'(!)             = ''              | ''                 | 'CC8180EMD00'                |'EC296_709_1575XA'| '1800UF' | '80V'         | '20%'       | 'DISCRETE' | 'CAP ELEC DIP1800U 80V(20%.105C,18*40)NPN'             | 'DIP'          | ''          | ''            | '20210909'
 '1800UF' | '80V'   | '20%'       | 'THLF'      | 'EMPTY'    | 'CC8180EMD00'(!)             = ''              | ''                 | 'CC8180EMD00'                |'EC296_709_1575XA'| '1800UF' | '80V'         | '20%'       | 'IO'       | 'CAP ELEC DIP1800U 80V(20%.105C,18*40)NPN'             | 'DIP'          | ''          | ''            | '20210909'
 '270UF'  | '16V'   | '20%'       | 'THLF'      | 'OSCON'    | 'CC72703MD27'(!)             = ''              | ''                 | 'CC72703MD27'                |'EC138_315_315XA'| '270UF'  | '16V'         | '20%'       | 'DISCRETE' | 'CAP OSCON DIP 270U 16V(+-20%,8*8)NPN'                 | 'DIP'          | ''          | ''            | '20210914'
 '270UF'  | '16V'   | '20%'       | 'THLF'      | 'EMPTY'    | 'CC72703MD27'(!)             = ''              | ''                 | 'CC72703MD27'                |'EC138_315_315XA'| '270UF'  | '16V'         | '20%'       | 'IO'       | 'CAP OSCON DIP 270U 16V(+-20%,8*8)NPN'                 | 'DIP'          | ''          | ''            | '20210914'
 '560UF'  | '2.5V'  | '20%'       | 'THLF'      | 'OSCON'    | 'CC7560JMD08'(!)             = ''              | ''                 | 'CC7560JMD08'                |'EC98_248_315XB'| '560UF'  | '2.5V'        | '20%'       | 'DISCRETE' | 'CAP OSCON 560U 2.5V(20%,105C,6.3*8)ESR5'              | 'DIP'          | ''          | ''            | '20210922'
 '560UF'  | '2.5V'  | '20%'       | 'THLF'      | 'EMPTY'    | 'CC7560JMD08'(!)             = ''              | ''                 | 'CC7560JMD08'                |'EC98_248_315XB'| '560UF'  | '2.5V'        | '20%'       | 'IO'       | 'CAP OSCON 560U 2.5V(20%,105C,6.3*8)ESR5'              | 'DIP'          | ''          | ''            | '20210922'
 '470UF'  | '16V'   | '20%'       | 'THLF'      | 'OSCON'    | 'CC74703MD26'(!)             = ''              | ''                 | 'CC74703MD26'                |'EC138_315_355'| '470UF'  | '16V'         | '20%'       | 'DISCRETE' | 'CAP OSCON DIP 470U 16V(20%,ESR16,8*9)APQ'             | 'DIP'          | ''          | ''            | '20210928'
 '470UF'  | '16V'   | '20%'       | 'THLF'      | 'EMPTY'    | 'CC74703MD26'(!)             = ''              | ''                 | 'CC74703MD26'                |'EC138_315_355'| '470UF'  | '16V'         | '20%'       | 'IO'       | 'CAP OSCON DIP 470U 16V(20%,ESR16,8*9)APQ'             | 'DIP'          | ''          | ''            | '20210928'
 '47UF'   | '100V'  | '20%'       | 'THLF'      | 'ALUM'     | 'CC64708MD03'(!)             = ''              | ''                 | 'CC64708MD03'                |'EC3-5_8-5_13'| '47UF'   | '100V'        | '20%'       | 'DISCRETE' | 'CAP ELEC DIP 47U100V(20%,105C,8*11.5)NPN'             | 'DIP'          | ''          | ''            | '20210930'
 '47UF'   | '100V'  | '20%'       | 'THLF'      | 'EMPTY'    | 'CC64708MD03'(!)             = ''              | ''                 | 'CC64708MD03'                |'EC3-5_8-5_13'| '47UF'   | '100V'        | '20%'       | 'IO'       | 'CAP ELEC DIP 47U100V(20%,105C,8*11.5)NPN'             | 'DIP'          | ''          | ''            | '20210930'
 '270UF'  | '80V'   | '20%'       | 'THLF'      | 'ALUM'     | 'CC7270EMD00'(!)             = ''              | ''                 | 'CC7270EMD00'                |'EC5_10-5_26-5'| '270UF'  | '80V'         | '20%'       | 'DISCRETE' | 'CAP ELEC DIP 270U 80V(20%,10*25)NPN'                  | 'DIP'          | ''          | ''            | '20210930'
 '270UF'  | '80V'   | '20%'       | 'THLF'      | 'EMPTY'    | 'CC7270EMD00'(!)             = ''              | ''                 | 'CC7270EMD00'                |'EC5_10-5_26-5'| '270UF'  | '80V'         | '20%'       | 'IO'       | 'CAP ELEC DIP 270U 80V(20%,10*25)NPN'                  | 'DIP'          | ''          | ''            | '20210930'
 '47UF'   | '100V'  | '20%'       | 'THLF'      | 'ALUM'     | 'CC64708MD06'(!)             = ''              | ''                 | 'CC64708MD06'                |'EC197_394_492'| '47UF'   | '100V'        | '20%'       | 'DISCRETE' | 'CAP ELEC DIP 47U 100V(20%,10*12.5)NPN'                | 'DIP'          | ''          | ''            | '20210930'
 '47UF'   | '100V'  | '20%'       | 'THLF'      | 'EMPTY'    | 'CC64708MD06'(!)             = ''              | ''                 | 'CC64708MD06'                |'EC197_394_492'| '47UF'   | '100V'        | '20%'       | 'IO'       | 'CAP ELEC DIP 47U 100V(20%,10*12.5)NPN'                | 'DIP'          | ''          | ''            | '20210930'
 '47UF'   | '100V'  | '20%'       | 'THLF'      | 'ALUM'     | 'CC64708MD04'(!)             = ''              | ''                 | 'CC64708MD04'                |'EC138_315_453XB'| '47UF'   | '100V'        | '20%'       | 'DISCRETE' | 'CAP ELEC DIP 47U100V(20%,105C,8*11.5)CSA'             | 'DIP'          | ''          | ''            | '20211013'
 '47UF'   | '100V'  | '20%'       | 'THLF'      | 'EMPTY'    | 'CC64708MD04'(!)             = ''              | ''                 | 'CC64708MD04'                |'EC138_315_453XB'| '47UF'   | '100V'        | '20%'       | 'IO'       | 'CAP ELEC DIP 47U100V(20%,105C,8*11.5)CSA'             | 'DIP'          | ''          | ''            | '20211013'
 '270UF'  | '80V'   | '20%'       | 'THLF'      | 'ALUM'     | 'CC7270EMD02'(!)             = ''              | ''                 | 'CC7270EMD02'                |'EC197_394_1044'| '270UF'  | '80V'         | '20%'       | 'DISCRETE' | 'CAP ELEC DIP 270U 80V(20%,10*25)CSA'                  | 'DIP'          | ''          | ''            | '20211013'
 '270UF'  | '80V'   | '20%'       | 'THLF'      | 'EMPTY'    | 'CC7270EMD02'(!)             = ''              | ''                 | 'CC7270EMD02'                |'EC197_394_1044'| '270UF'  | '80V'         | '20%'       | 'IO'       | 'CAP ELEC DIP 270U 80V(20%,10*25)CSA'                  | 'DIP'          | ''          | ''            | '20211013'
 '1800UF' | '80V'   | '20%'       | 'THLF'      | 'ALUM'     | 'CC8180EMD03'(!)             = ''              | ''                 | 'CC8180EMD03'                |'EC7-5_18-5_41-5'| '1800UF' | '80V'         | '20%'       | 'DISCRETE' | 'CAP ELEC DIP 1800U 80V(20%,105C,18*40)'               | 'DIP'          | ''          | ''            | '20211013'
 '1800UF' | '80V'   | '20%'       | 'THLF'      | 'EMPTY'    | 'CC8180EMD03'(!)             = ''              | ''                 | 'CC8180EMD03'                |'EC7-5_18-5_41-5'| '1800UF' | '80V'         | '20%'       | 'IO'       | 'CAP ELEC DIP 1800U 80V(20%,105C,18*40)'               | 'DIP'          | ''          | ''            | '20211013'
 '47UF'   | '100V'  | '20%'       | 'THLF'      | 'ALUM'     | 'CC64708MD05'(!)             = ''              | ''                 | 'CC64708MD05'                |'EC138_315_453XC'| '47UF'   | '100V'        | '20%'       | 'DISCRETE' | 'CAP ELEC DIP 47U100V(20%,105C,8*11.5)CPX'             | 'DIP'          | ''          | ''            | '20211014'
 '47UF'   | '100V'  | '20%'       | 'THLF'      | 'EMPTY'    | 'CC64708MD05'(!)             = ''              | ''                 | 'CC64708MD05'                |'EC138_315_453XC'| '47UF'   | '100V'        | '20%'       | 'IO'       | 'CAP ELEC DIP 47U100V(20%,105C,8*11.5)CPX'             | 'DIP'          | ''          | ''            | '20211014'
 '270UF'  | '80V'   | '20%'       | 'THLF'      | 'ALUM'     | 'CC7270EMD01'(!)             = ''              | ''                 | 'CC7270EMD01'                |'EC197_394_985XA'| '270UF'  | '80V'         | '20%'       | 'DISCRETE' | 'CAP ELEC DIP 270U 80V(20%,10*25)CPX'                  | 'DIP'          | ''          | ''            | '20211014'
 '270UF'  | '80V'   | '20%'       | 'THLF'      | 'EMPTY'    | 'CC7270EMD01'(!)             = ''              | ''                 | 'CC7270EMD01'                |'EC197_394_985XA'| '270UF'  | '80V'         | '20%'       | 'IO'       | 'CAP ELEC DIP 270U 80V(20%,10*25)CPX'                  | 'DIP'          | ''          | ''            | '20211014'
 '47UF'   | '100V'  | '20%'       | 'THLF'      | 'ALUM'     | 'CC64708MD07'(!)             = ''              | ''                 | 'CC64708MD07'                |'EC197_394_493'| '47UF'   | '100V'        | '20%'       | 'DISCRETE' | 'CAP ELEC DIP 47U 100V(20%,10*12.5)CPX'                | 'DIP'          | ''          | ''            | '20211014'
 '47UF'   | '100V'  | '20%'       | 'THLF'      | 'EMPTY'    | 'CC64708MD07'(!)             = ''              | ''                 | 'CC64708MD07'                |'EC197_394_493'| '47UF'   | '100V'        | '20%'       | 'IO'       | 'CAP ELEC DIP 47U 100V(20%,10*12.5)CPX'                | 'DIP'          | ''          | ''            | '20211014'
 '220UF'  | '4V'    | '20%'       | 'SMLF'      | 'SPCAP'    | 'CH122KM8801'(!)             = ''              | ''                 | 'CH122KM8801'                |'TAJ_SX'| '220UF'  | '4V'          | '20%'       | 'DISCRETE' | 'CAP CHIP 220U 4V(20%,7343,SPCAP)MAT'                  | 'SMT'          | ''          | ''            | '20211108'
 '220UF'  | '4V'    | '20%'       | 'SMLF'      | 'EMPTY'    | 'CH122KM8801'(!)             = ''              | ''                 | 'CH122KM8801'                |'TAJ_SX'| '220UF'  | '4V'          | '20%'       | 'IO'       | 'CAP CHIP 220U 4V(20%,7343,SPCAP)MAT'                  | 'SMT'          | ''          | ''            | '20211108'
 '220UF'  | '4V'    | '20%'       | 'SMLF'      | 'SPCAP'    | 'CH722KM8804'(!)             = ''              | ''                 | 'CH722KM8804'                |'TAJ_S_H87'| '220UF'  | '4V'          | '20%'       | 'DISCRETE' | 'CAP CHIP 220U 4V(+-20%,SPCAP,7343)APQ'                | 'SMT'          | ''          | ''            | '20220118'
 '220UF'  | '4V'    | '20%'       | 'SMLF'      | 'EMPTY'    | 'CH722KM8804'(!)             = ''              | ''                 | 'CH722KM8804'                |'TAJ_S_H87'| '220UF'  | '4V'          | '20%'       | 'IO'       | 'CAP CHIP 220U 4V(+-20%,SPCAP,7343)APQ'                | 'SMT'          | ''          | ''            | '20220118'
 '330UF'  | '2.5V'  | '20%'       | 'SMLF'      | 'SPCAP'    | 'CH733LM8817'(!)             = ''              | ''                 | 'CH733LM8817'                |'TAJ_SX'| '330UF'  | '2.5V'        | '20%'       | 'DISCRETE' | 'CAP CHIP 330U 2.5V(20%,SPCAP,7343)MAT'                | 'SMT'          | ''          | ''            | '20220121'
 '330UF'  | '2.5V'  | '20%'       | 'SMLF'      | 'EMPTY'    | 'CH733LM8817'(!)             = ''              | ''                 | 'CH733LM8817'                |'TAJ_SX'| '330UF'  | '2.5V'        | '20%'       | 'IO'       | 'CAP CHIP 330U 2.5V(20%,SPCAP,7343)MAT'                | 'SMT'          | ''          | ''            | '20220121'
 '330UF'  | '2.5V'  | '20%'       | 'SMLF'      | 'POSCAP'   | 'CH733LMI804'(!)             = ''              | ''                 | 'CH733LMI804'                |'TAJ_7343-20'| '330UF'  | '2.5V'        | '20%'       | 'DISCRETE' | 'CAPCHIP 330U2.5V(20%,POSCAP(TAN)7343)KEM'             | 'SMT'          | ''          | ''            | '20220124'
 '330UF'  | '2.5V'  | '20%'       | 'SMLF'      | 'EMPTY'    | 'CH733LMI804'(!)             = ''              | ''                 | 'CH733LMI804'                |'TAJ_7343-20'| '330UF'  | '2.5V'        | '20%'       | 'IO'       | 'CAPCHIP 330U2.5V(20%,POSCAP(TAN)7343)KEM'             | 'SMT'          | ''          | ''            | '20220124'
 '1000UF' | '80V'   | '20%'       | 'THLF'      | 'ALUM'     | 'CC8100EMD00'(!)             = ''              | ''                 | 'CC8100EMD00'                |'EC7-5_18-5_26-5'| '1000UF' | '80V'         | '20%'       | 'DISCRETE' | 'CAP ELEC DIP 1000UF 80V(+-20%,18*25)'                 | 'DIP'          | ''          | ''            | '20220124'
 '1000UF' | '80V'   | '20%'       | 'THLF'      | 'EMPTY'    | 'CC8100EMD00'(!)             = ''              | ''                 | 'CC8100EMD00'                |'EC7-5_18-5_26-5'| '1000UF' | '80V'         | '20%'       | 'IO'       | 'CAP ELEC DIP 1000UF 80V(+-20%,18*25)'                 | 'DIP'          | ''          | ''            | '20220124'
 '470UF'  | '16V'   | '20%'       | 'SMLF'      | 'OSCON'    | 'CC74703MD22'(!)             = ''              | ''                 | 'CC74703MD22'                |'EC181_394_496SXA'| '470UF'  | '16V'         | '20%'       | 'DISCRETE' | 'CAP OSCON SMD 470UF 16V(20%,10*12.4)TOW'              | 'SMT'          | ''          | ''            | '20220125'
 '470UF'  | '16V'   | '20%'       | 'SMLF'      | 'EMPTY'    | 'CC74703MD22'(!)             = ''              | ''                 | 'CC74703MD22'                |'EC181_394_496SXA'| '470UF'  | '16V'         | '20%'       | 'IO'       | 'CAP OSCON SMD 470UF 16V(20%,10*12.4)TOW'              | 'SMT'          | ''          | ''            | '20220125'
 '220UF'  | '2.5V'  | '20%'       | 'SMLF'      | 'TANT'     | 'CH722LM8613'(!)             = ''              | ''                 | 'CH722LM8613'                |'TAJ_B_T520B227M2R5ATE015'| '220UF'  | '2.5V'        | '20%'       | 'DISCRETE' | 'CAP CHIP 220U 2.5V(+-20%,ESR15,3528)H1.9'             | 'SMT'          | ''          | ''            | '20220223'
 '220UF'  | '2.5V'  | '20%'       | 'SMLF'      | 'EMPTY'    | 'CH722LM8613'(!)             = ''              | ''                 | 'CH722LM8613'                |'TAJ_B_T520B227M2R5ATE015'| '220UF'  | '2.5V'        | '20%'       | 'IO'       | 'CAP CHIP 220U 2.5V(+-20%,ESR15,3528)H1.9'             | 'SMT'          | ''          | ''            | '20220223'
 '560UF'  | '6.3V'  | '20%'       | 'SMLF'      | 'OSCON'    | 'CC75601MZ00'(!)             = ''              | ''                 | 'CC75601MZ00'                |'EC75_248_304S'| '560UF'  | '6.3V'        | '20%'       | 'DISCRETE' | 'CAP OSCON SMD 560U 6.3V(20%,6.3*7.7)'                 | 'SMT'          | ''          | ''            | '20220329'
 '560UF'  | '6.3V'  | '20%'       | 'SMLF'      | 'EMPTY'    | 'CC75601MZ00'(!)             = ''              | ''                 | 'CC75601MZ00'                |'EC75_248_304S'| '560UF'  | '6.3V'        | '20%'       | 'IO'       | 'CAP OSCON SMD 560U 6.3V(20%,6.3*7.7)'                 | 'SMT'          | ''          | ''            | '20220329'
 '270UF'  | '16V'   | '20%'       | 'SMLF'      | 'OSCON'    | 'CC72703MZ13'(!)             = ''              | ''                 | 'CC72703MZ13'                |'EC83_248_315S'| '270UF'  | '16V'         | '20%'       | 'DISCRETE' | 'CAPOS SMD 270U 16V(20%,ESR10,6.3*7.9)SAY'             | 'SMT'          | ''          | ''            | '20220413'
 '270UF'  | '16V'   | '20%'       | 'SMLF'      | 'EMPTY'    | 'CC72703MZ13'(!)             = ''              | ''                 | 'CC72703MZ13'                |'EC83_248_315S'| '270UF'  | '16V'         | '20%'       | 'IO'       | 'CAPOS SMD 270U 16V(20%,ESR10,6.3*7.9)SAY'             | 'SMT'          | ''          | ''            | '20220413'
 '470UF'  | '16V'   | '20%'       | 'SMLF'      | 'OSCON'    | 'CC74703MZ07'(!)             = ''              | ''                 | 'CC74703MZ07'                |'EC181_394_496SXA'| '470UF'  | '16V'         | '20%'       | 'DISCRETE' | 'CAP OSCON SMD 470UF 16V(20%,10*12.6)SAY'              | 'SMT'          | ''          | ''            | '20220422'
 '470UF'  | '16V'   | '20%'       | 'SMLF'      | 'EMPTY'    | 'CC74703MZ07'(!)             = ''              | ''                 | 'CC74703MZ07'                |'EC181_394_496SXA'| '470UF'  | '16V'         | '20%'       | 'IO'       | 'CAP OSCON SMD 470UF 16V(20%,10*12.6)SAY'              | 'SMT'          | ''          | ''            | '20220422'
 '100UF'  | '100V'  | '20%'       | 'THLF'      | 'ALUM'     | 'SP_CC71008MD07'(!)          = ''              | ''                 | 'CC71008MD07'                |'G_EC5_10-5_21-5'| '100UF'  | '100V'        | '20%'       | 'DISCRETE' | 'CAP ELEC DIP 100U 100V(20%,10*20)NPN_FOR SEL'         | 'DIP'          | ''          | ''            | '20220518'
 '100UF'  | '100V'  | '20%'       | 'THLF'      | 'EMPTY'    | 'SP_CC71008MD07'(!)          = ''              | ''                 | 'CC71008MD07'                |'G_EC5_10-5_21-5'| '100UF'  | '100V'        | '20%'       | 'IO'       | 'CAP ELEC DIP 100U 100V(20%,10*20)NPN_FOR SEL'         | 'DIP'          | ''          | ''            | '20220518'
 '470UF'  | '16V'   | '20%'       | 'THLF'      | 'OSCON'    | 'CC74703MD25'(!)             = ''              | ''                 | 'CC74703MD25'                |'EC3-5_8-5_9'| '470UF'  | '16V'         | '20%'       | 'DISCRETE' | 'CAP OSCON DIP 470U 16V(20%,ESR16,8*8)NPN'             | 'DIP'          | ''          | ''            | '20220601'
 '470UF'  | '16V'   | '20%'       | 'THLF'      | 'EMPTY'    | 'CC74703MD25'(!)             = ''              | ''                 | 'CC74703MD25'                |'EC3-5_8-5_9'| '470UF'  | '16V'         | '20%'       | 'IO'       | 'CAP OSCON DIP 470U 16V(20%,ESR16,8*8)NPN'             | 'DIP'          | ''          | ''            | '20220601'
 '270UF'  | '25V'   | '20%'       | 'SMLF'      | 'OSCON'    | 'CC72704MZ00'(!)             = ''              | ''                 | 'CC72704MZ00'                |'EC126_315_469SXA'| '270UF'  | '25V'         | '20%'       | 'DISCRETE' | 'CAP OSCON 270U,25V(20%,125C,8*11.9)SAY'               | 'SMT'          | ''          | ''            | '20220701'
 '270UF'  | '25V'   | '20%'       | 'SMLF'      | 'EMPTY'    | 'CC72704MZ00'(!)             = ''              | ''                 | 'CC72704MZ00'                |'EC126_315_469SXA'| '270UF'  | '25V'         | '20%'       | 'IO'       | 'CAP OSCON 270U,25V(20%,125C,8*11.9)SAY'               | 'SMT'          | ''          | ''            | '20220701'
 '680UF'  | '2.5V'  | '20%'       | 'SMLF'      | 'POSCAP'   | 'CH768LMI802'(!)             = ''              | ''                 | 'CH768LMI802'                |'TAJ_7343-20_H122'| '680UF'  | '2.5V'        | '20%'       | 'DISCRETE' | 'CAPCHIP 680U2.5V(20%,POSCAP(TAN)7343)KEM'             | 'SMT'          | ''          | ''            | '20220928'
 '680UF'  | '2.5V'  | '20%'       | 'SMLF'      | 'EMPTY'    | 'CH768LMI802'(!)             = ''              | ''                 | 'CH768LMI802'                |'TAJ_7343-20_H122'| '680UF'  | '2.5V'        | '20%'       | 'IO'       | 'CAPCHIP 680U2.5V(20%,POSCAP(TAN)7343)KEM'             | 'SMT'          | ''          | ''            | '20220928'
 '470UF'  | '2.5V'  | '20%'       | 'SMLF'      | 'SPCAP'    | 'CH747LM8827'(!)             = ''              | ''                 | 'CH747LM8827'                |'TAJ_S'| '470UF'  | '2.5V'        | '20%'       | 'DISCRETE' | 'CAP CHIP 470U 2.5V(+-20%,7343,SPCAP)APQ'              | 'SMT'          | ''          | ''            | '20221114'
 '470UF'  | '2.5V'  | '20%'       | 'SMLF'      | 'EMPTY'    | 'CH747LM8827'(!)             = ''              | ''                 | 'CH747LM8827'                |'TAJ_S'| '470UF'  | '2.5V'        | '20%'       | 'IO'       | 'CAP CHIP 470U 2.5V(+-20%,7343,SPCAP)APQ'              | 'SMT'          | ''          | ''            | '20221114'
 '220UF'  | '6.3V'  | '20%'       | 'SMLF'      | 'SPCAP'    | 'CH7221M8818'(!)             = ''              | ''                 | 'CH7221M8818'                |'TAJ_S'| '220UF'  | '6.3V'        | '20%'       | 'DISCRETE' | 'CAP CHIP 220UF 6.3V(20%,SPCAP,7343)APQ'               | 'SMT'          | ''          | ''            | '20221114'
 '220UF'  | '6.3V'  | '20%'       | 'SMLF'      | 'EMPTY'    | 'CH7221M8818'(!)             = ''              | ''                 | 'CH7221M8818'                |'TAJ_S'| '220UF'  | '6.3V'        | '20%'       | 'IO'       | 'CAP CHIP 220UF 6.3V(20%,SPCAP,7343)APQ'               | 'SMT'          | ''          | ''            | '20221114'
 '680UF'  | '80V'   | '20%'       | 'SMLF'      | 'ALUM'     | 'CC7680EMZ01'(!)             = ''              | ''                 | 'CC7680EMZ01'                |'EC256_709_847S'| '680UF'  | '80V'         | '20%'       | 'DISCRETE' | 'CAP ELEC SMD 680UF 80V(+-20%,18*21.5)'                | 'SMT'          | ''          | ''            | '20221123'
 '680UF'  | '80V'   | '20%'       | 'SMLF'      | 'EMPTY'    | 'CC7680EMZ01'(!)             = ''              | ''                 | 'CC7680EMZ01'                |'EC256_709_847S'| '680UF'  | '80V'         | '20%'       | 'IO'       | 'CAP ELEC SMD 680UF 80V(+-20%,18*21.5)'                | 'SMT'          | ''          | ''            | '20221123'
 '270UF'  | '25V'   | '20%'       | 'SMLF'      | 'OSCON'    | 'CC72704MZ06'(!)             = ''              | ''                 | 'CC72704MZ06'                |'EC126_315_473S'| '270UF'  | '25V'         | '20%'       | 'DISCRETE' | 'CAP OSCON SMD 270U 25V(20%,105C,8*12)APQ'             | 'SMT'          | ''          | ''            | '20221123'
 '270UF'  | '25V'   | '20%'       | 'SMLF'      | 'EMPTY'    | 'CC72704MZ06'(!)             = ''              | ''                 | 'CC72704MZ06'                |'EC126_315_473S'| '270UF'  | '25V'         | '20%'       | 'IO'       | 'CAP OSCON SMD 270U 25V(20%,105C,8*12)APQ'             | 'SMT'          | ''          | ''            | '20221123'
 '270UF'  | '16V'   | '20%'       | 'SMLF'      | 'OSCON'    | 'CC72703MZ16'(!)             = ''              | ''                 | 'CC72703MZ16'                |'EC83_248_315S'| '270UF'  | '16V'         | '20%'       | 'DISCRETE' | 'CAP OS SMD 270U16V(20%,ESR13,6.3*7.7)CSA'             | 'SMT'          | ''          | ''            | '20221214'
 '270UF'  | '16V'   | '20%'       | 'SMLF'      | 'EMPTY'    | 'CC72703MZ16'(!)             = ''              | ''                 | 'CC72703MZ16'                |'EC83_248_315S'| '270UF'  | '16V'         | '20%'       | 'IO'       | 'CAP OS SMD 270U16V(20%,ESR13,6.3*7.7)CSA'             | 'SMT'          | ''          | ''            | '20221214'
 '220UF'  | '6.3V'  | '20%'       | 'SMLF'      | 'OSCON'    | 'CC72201MZ40'(!)             = ''              | ''                 | 'CC72201MZ40'                |'EC56_197_229SXA'| '220UF'  | '6.3V'        | '20%'       | 'DISCRETE' | 'CAP OS SMD 220U6.3V(20%,ESR12,5*5.7)CSA'              | 'SMT'          | ''          | ''            | '20221214'
 '220UF'  | '6.3V'  | '20%'       | 'SMLF'      | 'EMPTY'    | 'CC72201MZ40'(!)             = ''              | ''                 | 'CC72201MZ40'                |'EC56_197_229SXA'| '220UF'  | '6.3V'        | '20%'       | 'IO'       | 'CAP OS SMD 220U6.3V(20%,ESR12,5*5.7)CSA'              | 'SMT'          | ''          | ''            | '20221214'
 '390UF'  | '2.5V'  | '20%'       | 'SMLF'      | 'OSCON'    | 'CC7390JMZ15'(!)             = ''              | ''                 | 'CC7390JMZ15'                |'EC56_197_229SXA'| '390UF'  | '2.5V'        | '20%'       | 'DISCRETE' | 'CAP OS SMD 390U 2.5V(20%,ESR10,5*5.7)CSA'             | 'SMT'          | ''          | ''            | '20221214'
 '390UF'  | '2.5V'  | '20%'       | 'SMLF'      | 'EMPTY'    | 'CC7390JMZ15'(!)             = ''              | ''                 | 'CC7390JMZ15'                |'EC56_197_229SXA'| '390UF'  | '2.5V'        | '20%'       | 'IO'       | 'CAP OS SMD 390U 2.5V(20%,ESR10,5*5.7)CSA'             | 'SMT'          | ''          | ''            | '20221214'
 '470UF'  | '2V'    | '20%'       | 'SMLF'      | 'SPCAP'    | 'CH747RM8826'(!)             = ''              | ''                 | 'CH747RM8826'                |'TAJ_7343-20_H83'| '470UF'  | '2V'          | '20%'       | 'DISCRETE' | 'CAP CHIP 470U 2V(20%,SPCAP,ESR3,7343)KEM'             | 'SMT'          | ''          | ''            | '20221214'
 '470UF'  | '2V'    | '20%'       | 'SMLF'      | 'EMPTY'    | 'CH747RM8826'(!)             = ''              | ''                 | 'CH747RM8826'                |'TAJ_7343-20_H83'| '470UF'  | '2V'          | '20%'       | 'IO'       | 'CAP CHIP 470U 2V(20%,SPCAP,ESR3,7343)KEM'             | 'SMT'          | ''          | ''            | '20221214'
 '330UF'  | '2V'    | '20%'       | 'SMLF'      | 'SPCAP'    | 'CH733RM8830'(!)             = ''              | ''                 | 'CH733RM8830'                |'TAJ_7343-20'| '330UF'  | '2V'          | '20%'       | 'DISCRETE' | 'CAP CHIP 330U 2V(+-20%,SPCAP,7343)KEM'                | 'SMT'          | ''          | ''            | '20221226'
 '330UF'  | '2V'    | '20%'       | 'SMLF'      | 'EMPTY'    | 'CH733RM8830'(!)             = ''              | ''                 | 'CH733RM8830'                |'TAJ_7343-20'| '330UF'  | '2V'          | '20%'       | 'IO'       | 'CAP CHIP 330U 2V(+-20%,SPCAP,7343)KEM'                | 'SMT'          | ''          | ''            | '20221226'
 '220UF'  | '4V'    | '20%'       | 'SMLF'      | 'POSCAP'   | 'CH722KMI801'(!)             = ''              | ''                 | 'CH722KMI801'                |'TAJ_7343-20'| '220UF'  | '4V'          | '20%'       | 'DISCRETE' | 'CAP CHIP 220U 4V(20%,POSCAP(TAN,7343)KEM'             | 'SMT'          | ''          | ''            | '20230119'
 '220UF'  | '4V'    | '20%'       | 'SMLF'      | 'EMPTY'    | 'CH722KMI801'(!)             = ''              | ''                 | 'CH722KMI801'                |'TAJ_7343-20'| '220UF'  | '4V'          | '20%'       | 'IO'       | 'CAP CHIP 220U 4V(20%,POSCAP(TAN,7343)KEM'             | 'SMT'          | ''          | ''            | '20230119'
 '560UF'  | '2V'    | '20%'       | 'SMLF'      | 'SPCAP'    | 'CH756RM8805'(!)             = ''              | 'Comp-Approve'     | 'CH756RM8805'                | 'TAJ_DXC'                  | '560UF'  | '2V'          | '20%'       | 'DISCRETE' | 'CAPCHIP 560U 2V(20%,SPCAP,ESR=3,7343)MAT'             | 'SMT'          | ''          | ''            | '20230201'
 '560UF'  | '2V'    | '20%'       | 'SMLF'      | 'EMPTY'    | 'CH756RM8805'(!)             = ''              | 'Comp-Approve'     | 'CH756RM8805'                | 'TAJ_DXC'                  | '560UF'  | '2V'          | '20%'       | 'IO'       | 'CAPCHIP 560U 2V(20%,SPCAP,ESR=3,7343)MAT'             | 'SMT'          | ''          | ''            | '20230201'
 '1500UF' | '2.5V'  | '20%'       | 'SMLF'      | 'POSCAP'   | 'CH815LMI800'(!)             = ''               | ''               | 'CH815LMI800'                |'TAJ_7343-20_H170'| '1500UF' | '2.5V'        | '20%'       | 'DISCRETE' | 'CAP CHIP 1500U 2.5V(20%,POSCAP,7343)'                 | 'SMT'          | ''          | ''            | '20230328'
 '1500UF' | '2.5V'  | '20%'       | 'SMLF'      | 'EMPTY'    | 'CH815LMI800'(!)             = ''               | ''               | 'CH815LMI800'                |'TAJ_7343-20_H170'| '1500UF' | '2.5V'        | '20%'       | 'IO'       | 'CAP CHIP 1500U 2.5V(20%,POSCAP,7343)'                 | 'SMT'          | ''          | ''            | '20230328'

END_PART

END.

